FILE_TYPE = MACRO_DRAWING;
SET COLOR_WIRE YELLOW;
SET COLOR_PROP MONO;
SET COLOR_DOT WHITE;
SET COLOR_ARC YELLOW;
SET COLOR_BODY GREEN;
SET COLOR_NOTE MONO;
SET PROP_DISPLAY VALUE;
SET PAGE_NUMBER P67;
FORCEADD OFFPAGE..1
(-6700 3625);
FORCEPROP 2 LAST $XR0 33 
J 0
(-6951 3625);
DISPLAY 0.638298 (-6951 3625);
PAINT MONO (-6951 3625);
FORCEPROP 2 LAST CDS_LIB mstr_standard
J 0
(-6700 3625);
PAINT MONO (-6700 3625);
DISPLAY INVISIBLE (-6700 3625);
FORCEPROP 1 LAST OFFPAGE TRUE
J 0
(-6375 3500);
DISPLAY 1.170213 (-6375 3500);
PAINT GREEN (-6375 3500);
DISPLAY INVISIBLE (-6375 3500);
FORCEPROP 1 LAST COMMENT_BODY TRUE
J 0
(-6575 3525);
DISPLAY 1.170213 (-6575 3525);
PAINT GREEN (-6575 3525);
DISPLAY INVISIBLE (-6575 3525);
FORCEPROP 2 LAST PATH I1
J 0
(-6650 3700);
DISPLAY 1.021277 (-6650 3700);
PAINT ORANGE (-6650 3700);
DISPLAY INVISIBLE (-6650 3700);
FORCEADD TAP..1
R 2
(-5225 2125);
FORCEPROP 3 LASTPIN (-5175 2125) SIG_NAME UPI_CPU0_CPU1_P0P0_DP<11>
J 0
(-5165 2135);
DISPLAY 0.659574 (-5165 2135);
PAINT MONO (-5165 2135);
DISPLAY INVISIBLE (-5165 2135);
FORCEPROP 1 LASTPIN (-5175 2125) BN 11
J 2
(-5163 2133);
DISPLAY 0.617021 (-5163 2133);
PAINT GREEN (-5163 2133);
FORCEPROP 2 LAST CDS_LIB mstr_standard
J 0
(-5225 2125);
PAINT MONO (-5225 2125);
DISPLAY INVISIBLE (-5225 2125);
FORCEPROP 1 LAST BODY_TYPE PLUMBING
J 2
(-5225 2175);
DISPLAY 1.446809 (-5225 2175);
PAINT GREEN (-5225 2175);
DISPLAY INVISIBLE (-5225 2175);
FORCEPROP 1 LAST HDL_TAP TRUE
J 2
(-5550 2000);
DISPLAY 1.446809 (-5550 2000);
PAINT GREEN (-5550 2000);
DISPLAY INVISIBLE (-5550 2000);
FORCEPROP 1 LAST PATH I100
J 2
(-5223 2125);
DISPLAY 0.872340 (-5223 2125);
PAINT GREEN (-5223 2125);
DISPLAY INVISIBLE (-5223 2125);
FORCEADD TAP..1
R 2
(-5225 2025);
FORCEPROP 3 LASTPIN (-5175 2025) SIG_NAME UPI_CPU0_CPU1_P0P0_DP<9>
J 0
(-5165 2035);
DISPLAY 0.659574 (-5165 2035);
PAINT MONO (-5165 2035);
DISPLAY INVISIBLE (-5165 2035);
FORCEPROP 1 LASTPIN (-5175 2025) BN 9
J 2
(-5163 2033);
DISPLAY 0.617021 (-5163 2033);
PAINT GREEN (-5163 2033);
FORCEPROP 2 LAST CDS_LIB mstr_standard
J 0
(-5225 2025);
PAINT MONO (-5225 2025);
DISPLAY INVISIBLE (-5225 2025);
FORCEPROP 1 LAST BODY_TYPE PLUMBING
J 2
(-5225 2075);
DISPLAY 1.446809 (-5225 2075);
PAINT GREEN (-5225 2075);
DISPLAY INVISIBLE (-5225 2075);
FORCEPROP 1 LAST HDL_TAP TRUE
J 2
(-5550 1900);
DISPLAY 1.446809 (-5550 1900);
PAINT GREEN (-5550 1900);
DISPLAY INVISIBLE (-5550 1900);
FORCEPROP 1 LAST PATH I101
J 2
(-5223 2025);
DISPLAY 0.872340 (-5223 2025);
PAINT GREEN (-5223 2025);
DISPLAY INVISIBLE (-5223 2025);
FORCEADD TAP..1
R 2
(-5225 1975);
FORCEPROP 3 LASTPIN (-5175 1975) SIG_NAME UPI_CPU0_CPU1_P0P0_DP<8>
J 0
(-5165 1985);
DISPLAY 0.659574 (-5165 1985);
PAINT MONO (-5165 1985);
DISPLAY INVISIBLE (-5165 1985);
FORCEPROP 1 LASTPIN (-5175 1975) BN 8
J 2
(-5163 1983);
DISPLAY 0.617021 (-5163 1983);
PAINT GREEN (-5163 1983);
FORCEPROP 2 LAST CDS_LIB mstr_standard
J 0
(-5225 1975);
PAINT MONO (-5225 1975);
DISPLAY INVISIBLE (-5225 1975);
FORCEPROP 1 LAST BODY_TYPE PLUMBING
J 2
(-5225 2025);
DISPLAY 1.446809 (-5225 2025);
PAINT GREEN (-5225 2025);
DISPLAY INVISIBLE (-5225 2025);
FORCEPROP 1 LAST HDL_TAP TRUE
J 2
(-5550 1850);
DISPLAY 1.446809 (-5550 1850);
PAINT GREEN (-5550 1850);
DISPLAY INVISIBLE (-5550 1850);
FORCEPROP 1 LAST PATH I102
J 2
(-5223 1975);
DISPLAY 0.872340 (-5223 1975);
PAINT GREEN (-5223 1975);
DISPLAY INVISIBLE (-5223 1975);
FORCEADD TAP..1
R 2
(-5225 1925);
FORCEPROP 3 LASTPIN (-5175 1925) SIG_NAME UPI_CPU0_CPU1_P0P0_DP<7>
J 0
(-5165 1935);
DISPLAY 0.659574 (-5165 1935);
PAINT MONO (-5165 1935);
DISPLAY INVISIBLE (-5165 1935);
FORCEPROP 1 LASTPIN (-5175 1925) BN 7
J 2
(-5163 1933);
DISPLAY 0.617021 (-5163 1933);
PAINT GREEN (-5163 1933);
FORCEPROP 2 LAST CDS_LIB mstr_standard
J 0
(-5225 1925);
PAINT MONO (-5225 1925);
DISPLAY INVISIBLE (-5225 1925);
FORCEPROP 1 LAST BODY_TYPE PLUMBING
J 2
(-5225 1975);
DISPLAY 1.446809 (-5225 1975);
PAINT GREEN (-5225 1975);
DISPLAY INVISIBLE (-5225 1975);
FORCEPROP 1 LAST HDL_TAP TRUE
J 2
(-5550 1800);
DISPLAY 1.446809 (-5550 1800);
PAINT GREEN (-5550 1800);
DISPLAY INVISIBLE (-5550 1800);
FORCEPROP 1 LAST PATH I103
J 2
(-5223 1925);
DISPLAY 0.872340 (-5223 1925);
PAINT GREEN (-5223 1925);
DISPLAY INVISIBLE (-5223 1925);
FORCEADD TAP..1
R 2
(-5225 1875);
FORCEPROP 3 LASTPIN (-5175 1875) SIG_NAME UPI_CPU0_CPU1_P0P0_DP<6>
J 0
(-5165 1885);
DISPLAY 0.659574 (-5165 1885);
PAINT MONO (-5165 1885);
DISPLAY INVISIBLE (-5165 1885);
FORCEPROP 1 LASTPIN (-5175 1875) BN 6
J 2
(-5163 1883);
DISPLAY 0.617021 (-5163 1883);
PAINT GREEN (-5163 1883);
FORCEPROP 2 LAST CDS_LIB mstr_standard
J 0
(-5225 1875);
PAINT MONO (-5225 1875);
DISPLAY INVISIBLE (-5225 1875);
FORCEPROP 1 LAST BODY_TYPE PLUMBING
J 2
(-5225 1925);
DISPLAY 1.446809 (-5225 1925);
PAINT GREEN (-5225 1925);
DISPLAY INVISIBLE (-5225 1925);
FORCEPROP 1 LAST HDL_TAP TRUE
J 2
(-5550 1750);
DISPLAY 1.446809 (-5550 1750);
PAINT GREEN (-5550 1750);
DISPLAY INVISIBLE (-5550 1750);
FORCEPROP 1 LAST PATH I104
J 2
(-5223 1875);
DISPLAY 0.872340 (-5223 1875);
PAINT GREEN (-5223 1875);
DISPLAY INVISIBLE (-5223 1875);
FORCEADD TAP..1
R 2
(-5225 1825);
FORCEPROP 3 LASTPIN (-5175 1825) SIG_NAME UPI_CPU0_CPU1_P0P0_DP<5>
J 0
(-5165 1835);
DISPLAY 0.659574 (-5165 1835);
PAINT MONO (-5165 1835);
DISPLAY INVISIBLE (-5165 1835);
FORCEPROP 1 LASTPIN (-5175 1825) BN 5
J 2
(-5163 1833);
DISPLAY 0.617021 (-5163 1833);
PAINT GREEN (-5163 1833);
FORCEPROP 2 LAST CDS_LIB mstr_standard
J 0
(-5225 1825);
PAINT MONO (-5225 1825);
DISPLAY INVISIBLE (-5225 1825);
FORCEPROP 1 LAST BODY_TYPE PLUMBING
J 2
(-5225 1875);
DISPLAY 1.446809 (-5225 1875);
PAINT GREEN (-5225 1875);
DISPLAY INVISIBLE (-5225 1875);
FORCEPROP 1 LAST HDL_TAP TRUE
J 2
(-5550 1700);
DISPLAY 1.446809 (-5550 1700);
PAINT GREEN (-5550 1700);
DISPLAY INVISIBLE (-5550 1700);
FORCEPROP 1 LAST PATH I105
J 2
(-5223 1825);
DISPLAY 0.872340 (-5223 1825);
PAINT GREEN (-5223 1825);
DISPLAY INVISIBLE (-5223 1825);
FORCEADD TAP..1
R 2
(-5225 2675);
FORCEPROP 3 LASTPIN (-5175 2675) SIG_NAME UPI_CPU0_CPU1_P0P0_DP<1>
J 0
(-5165 2685);
DISPLAY 0.659574 (-5165 2685);
PAINT MONO (-5165 2685);
DISPLAY INVISIBLE (-5165 2685);
FORCEPROP 1 LASTPIN (-5175 2675) BN 1
J 2
(-5163 2683);
DISPLAY 0.617021 (-5163 2683);
PAINT GREEN (-5163 2683);
FORCEPROP 2 LAST CDS_LIB mstr_standard
J 0
(-5225 2675);
PAINT MONO (-5225 2675);
DISPLAY INVISIBLE (-5225 2675);
FORCEPROP 1 LAST BODY_TYPE PLUMBING
J 2
(-5225 2725);
DISPLAY 1.446809 (-5225 2725);
PAINT GREEN (-5225 2725);
DISPLAY INVISIBLE (-5225 2725);
FORCEPROP 1 LAST HDL_TAP TRUE
J 2
(-5550 2550);
DISPLAY 1.446809 (-5550 2550);
PAINT GREEN (-5550 2550);
DISPLAY INVISIBLE (-5550 2550);
FORCEPROP 1 LAST PATH I106
J 2
(-5223 2675);
DISPLAY 0.872340 (-5223 2675);
PAINT GREEN (-5223 2675);
DISPLAY INVISIBLE (-5223 2675);
FORCEADD TAP..1
R 2
(-5225 1575);
FORCEPROP 3 LASTPIN (-5175 1575) SIG_NAME UPI_CPU0_CPU1_P0P0_DP<0>
J 0
(-5165 1585);
DISPLAY 0.659574 (-5165 1585);
PAINT MONO (-5165 1585);
DISPLAY INVISIBLE (-5165 1585);
FORCEPROP 1 LASTPIN (-5175 1575) BN 0
J 2
(-5163 1583);
DISPLAY 0.617021 (-5163 1583);
PAINT GREEN (-5163 1583);
FORCEPROP 2 LAST CDS_LIB mstr_standard
J 0
(-5225 1575);
PAINT MONO (-5225 1575);
DISPLAY INVISIBLE (-5225 1575);
FORCEPROP 1 LAST BODY_TYPE PLUMBING
J 2
(-5225 1625);
DISPLAY 1.446809 (-5225 1625);
PAINT GREEN (-5225 1625);
DISPLAY INVISIBLE (-5225 1625);
FORCEPROP 1 LAST HDL_TAP TRUE
J 2
(-5550 1450);
DISPLAY 1.446809 (-5550 1450);
PAINT GREEN (-5550 1450);
DISPLAY INVISIBLE (-5550 1450);
FORCEPROP 1 LAST PATH I107
J 2
(-5223 1575);
DISPLAY 0.872340 (-5223 1575);
PAINT GREEN (-5223 1575);
DISPLAY INVISIBLE (-5223 1575);
FORCEADD TAP..1
R 2
(-5225 3275);
FORCEPROP 3 LASTPIN (-5175 3275) SIG_NAME UPI_CPU0_CPU1_P0P0_DP<13>
J 0
(-5165 3285);
DISPLAY 0.659574 (-5165 3285);
PAINT MONO (-5165 3285);
DISPLAY INVISIBLE (-5165 3285);
FORCEPROP 1 LASTPIN (-5175 3275) BN 13
J 2
(-5163 3283);
DISPLAY 0.617021 (-5163 3283);
PAINT GREEN (-5163 3283);
FORCEPROP 2 LAST CDS_LIB mstr_standard
J 0
(-5225 3275);
PAINT MONO (-5225 3275);
DISPLAY INVISIBLE (-5225 3275);
FORCEPROP 1 LAST BODY_TYPE PLUMBING
J 2
(-5225 3325);
DISPLAY 1.446809 (-5225 3325);
PAINT GREEN (-5225 3325);
DISPLAY INVISIBLE (-5225 3325);
FORCEPROP 1 LAST HDL_TAP TRUE
J 2
(-5550 3150);
DISPLAY 1.446809 (-5550 3150);
PAINT GREEN (-5550 3150);
DISPLAY INVISIBLE (-5550 3150);
FORCEPROP 1 LAST PATH I108
J 2
(-5223 3275);
DISPLAY 0.872340 (-5223 3275);
PAINT GREEN (-5223 3275);
DISPLAY INVISIBLE (-5223 3275);
FORCEADD TAP..1
(-2575 3575);
FORCEPROP 3 LASTPIN (-2625 3575) SIG_NAME UPI_CPU1_CPU0_P0P0_DN<19>
J 0
(-2615 3585);
DISPLAY 0.659574 (-2615 3585);
PAINT MONO (-2615 3585);
DISPLAY INVISIBLE (-2615 3585);
FORCEPROP 1 LASTPIN (-2625 3575) BN 19
J 0
(-2637 3583);
DISPLAY 0.617021 (-2637 3583);
PAINT GREEN (-2637 3583);
FORCEPROP 2 LAST CDS_LIB mstr_standard
J 2
(-2575 3575);
PAINT MONO (-2575 3575);
DISPLAY INVISIBLE (-2575 3575);
FORCEPROP 1 LAST BODY_TYPE PLUMBING
J 0
(-2575 3625);
DISPLAY 1.446809 (-2575 3625);
PAINT GREEN (-2575 3625);
DISPLAY INVISIBLE (-2575 3625);
FORCEPROP 1 LAST HDL_TAP TRUE
J 0
(-2250 3450);
DISPLAY 1.446809 (-2250 3450);
PAINT GREEN (-2250 3450);
DISPLAY INVISIBLE (-2250 3450);
FORCEPROP 1 LAST PATH I109
J 0
(-2577 3575);
DISPLAY 0.872340 (-2577 3575);
PAINT GREEN (-2577 3575);
DISPLAY INVISIBLE (-2577 3575);
FORCEADD TAP..1
(-2575 3425);
FORCEPROP 3 LASTPIN (-2625 3425) SIG_NAME UPI_CPU1_CPU0_P0P0_DN<16>
J 0
(-2615 3435);
DISPLAY 0.659574 (-2615 3435);
PAINT MONO (-2615 3435);
DISPLAY INVISIBLE (-2615 3435);
FORCEPROP 1 LASTPIN (-2625 3425) BN 16
J 0
(-2637 3433);
DISPLAY 0.617021 (-2637 3433);
PAINT GREEN (-2637 3433);
FORCEPROP 2 LAST CDS_LIB mstr_standard
J 0
(-2575 3425);
PAINT MONO (-2575 3425);
DISPLAY INVISIBLE (-2575 3425);
FORCEPROP 1 LAST BODY_TYPE PLUMBING
J 0
(-2575 3475);
DISPLAY 1.446809 (-2575 3475);
PAINT GREEN (-2575 3475);
DISPLAY INVISIBLE (-2575 3475);
FORCEPROP 1 LAST HDL_TAP TRUE
J 0
(-2250 3300);
DISPLAY 1.446809 (-2250 3300);
PAINT GREEN (-2250 3300);
DISPLAY INVISIBLE (-2250 3300);
FORCEPROP 1 LAST PATH I110
J 0
(-2577 3425);
DISPLAY 0.872340 (-2577 3425);
PAINT GREEN (-2577 3425);
DISPLAY INVISIBLE (-2577 3425);
FORCEADD TAP..1
(-2575 3375);
FORCEPROP 3 LASTPIN (-2625 3375) SIG_NAME UPI_CPU1_CPU0_P0P0_DN<15>
J 0
(-2615 3385);
DISPLAY 0.659574 (-2615 3385);
PAINT MONO (-2615 3385);
DISPLAY INVISIBLE (-2615 3385);
FORCEPROP 1 LASTPIN (-2625 3375) BN 15
J 0
(-2637 3383);
DISPLAY 0.617021 (-2637 3383);
PAINT GREEN (-2637 3383);
FORCEPROP 2 LAST CDS_LIB mstr_standard
J 0
(-2575 3375);
PAINT MONO (-2575 3375);
DISPLAY INVISIBLE (-2575 3375);
FORCEPROP 1 LAST BODY_TYPE PLUMBING
J 0
(-2575 3425);
DISPLAY 1.446809 (-2575 3425);
PAINT GREEN (-2575 3425);
DISPLAY INVISIBLE (-2575 3425);
FORCEPROP 1 LAST HDL_TAP TRUE
J 0
(-2250 3250);
DISPLAY 1.446809 (-2250 3250);
PAINT GREEN (-2250 3250);
DISPLAY INVISIBLE (-2250 3250);
FORCEPROP 1 LAST PATH I111
J 0
(-2577 3375);
DISPLAY 0.872340 (-2577 3375);
PAINT GREEN (-2577 3375);
DISPLAY INVISIBLE (-2577 3375);
FORCEADD TAP..1
(-2575 3275);
FORCEPROP 3 LASTPIN (-2625 3275) SIG_NAME UPI_CPU1_CPU0_P0P0_DN<13>
J 0
(-2615 3285);
DISPLAY 0.659574 (-2615 3285);
PAINT MONO (-2615 3285);
DISPLAY INVISIBLE (-2615 3285);
FORCEPROP 1 LASTPIN (-2625 3275) BN 13
J 0
(-2637 3283);
DISPLAY 0.617021 (-2637 3283);
PAINT GREEN (-2637 3283);
FORCEPROP 2 LAST CDS_LIB mstr_standard
J 0
(-2575 3275);
PAINT MONO (-2575 3275);
DISPLAY INVISIBLE (-2575 3275);
FORCEPROP 1 LAST BODY_TYPE PLUMBING
J 0
(-2575 3325);
DISPLAY 1.446809 (-2575 3325);
PAINT GREEN (-2575 3325);
DISPLAY INVISIBLE (-2575 3325);
FORCEPROP 1 LAST HDL_TAP TRUE
J 0
(-2250 3150);
DISPLAY 1.446809 (-2250 3150);
PAINT GREEN (-2250 3150);
DISPLAY INVISIBLE (-2250 3150);
FORCEPROP 1 LAST PATH I112
J 0
(-2577 3275);
DISPLAY 0.872340 (-2577 3275);
PAINT GREEN (-2577 3275);
DISPLAY INVISIBLE (-2577 3275);
FORCEADD TAP..1
(-2575 3225);
FORCEPROP 3 LASTPIN (-2625 3225) SIG_NAME UPI_CPU1_CPU0_P0P0_DN<12>
J 0
(-2615 3235);
DISPLAY 0.659574 (-2615 3235);
PAINT MONO (-2615 3235);
DISPLAY INVISIBLE (-2615 3235);
FORCEPROP 1 LASTPIN (-2625 3225) BN 12
J 0
(-2637 3233);
DISPLAY 0.617021 (-2637 3233);
PAINT GREEN (-2637 3233);
FORCEPROP 2 LAST CDS_LIB mstr_standard
J 0
(-2575 3225);
PAINT MONO (-2575 3225);
DISPLAY INVISIBLE (-2575 3225);
FORCEPROP 1 LAST BODY_TYPE PLUMBING
J 0
(-2575 3275);
DISPLAY 1.446809 (-2575 3275);
PAINT GREEN (-2575 3275);
DISPLAY INVISIBLE (-2575 3275);
FORCEPROP 1 LAST HDL_TAP TRUE
J 0
(-2250 3100);
DISPLAY 1.446809 (-2250 3100);
PAINT GREEN (-2250 3100);
DISPLAY INVISIBLE (-2250 3100);
FORCEPROP 1 LAST PATH I113
J 0
(-2577 3225);
DISPLAY 0.872340 (-2577 3225);
PAINT GREEN (-2577 3225);
DISPLAY INVISIBLE (-2577 3225);
FORCEADD TAP..1
(-2575 3175);
FORCEPROP 3 LASTPIN (-2625 3175) SIG_NAME UPI_CPU1_CPU0_P0P0_DN<11>
J 0
(-2615 3185);
DISPLAY 0.659574 (-2615 3185);
PAINT MONO (-2615 3185);
DISPLAY INVISIBLE (-2615 3185);
FORCEPROP 1 LASTPIN (-2625 3175) BN 11
J 0
(-2637 3183);
DISPLAY 0.617021 (-2637 3183);
PAINT GREEN (-2637 3183);
FORCEPROP 2 LAST CDS_LIB mstr_standard
J 0
(-2575 3175);
PAINT MONO (-2575 3175);
DISPLAY INVISIBLE (-2575 3175);
FORCEPROP 1 LAST BODY_TYPE PLUMBING
J 0
(-2575 3225);
DISPLAY 1.446809 (-2575 3225);
PAINT GREEN (-2575 3225);
DISPLAY INVISIBLE (-2575 3225);
FORCEPROP 1 LAST HDL_TAP TRUE
J 0
(-2250 3050);
DISPLAY 1.446809 (-2250 3050);
PAINT GREEN (-2250 3050);
DISPLAY INVISIBLE (-2250 3050);
FORCEPROP 1 LAST PATH I114
J 0
(-2577 3175);
DISPLAY 0.872340 (-2577 3175);
PAINT GREEN (-2577 3175);
DISPLAY INVISIBLE (-2577 3175);
FORCEADD TAP..1
(-2575 3025);
FORCEPROP 3 LASTPIN (-2625 3025) SIG_NAME UPI_CPU1_CPU0_P0P0_DN<8>
J 0
(-2615 3035);
DISPLAY 0.659574 (-2615 3035);
PAINT MONO (-2615 3035);
DISPLAY INVISIBLE (-2615 3035);
FORCEPROP 1 LASTPIN (-2625 3025) BN 8
J 0
(-2637 3033);
DISPLAY 0.617021 (-2637 3033);
PAINT GREEN (-2637 3033);
FORCEPROP 2 LAST CDS_LIB mstr_standard
J 0
(-2575 3025);
PAINT MONO (-2575 3025);
DISPLAY INVISIBLE (-2575 3025);
FORCEPROP 1 LAST BODY_TYPE PLUMBING
J 0
(-2575 3075);
DISPLAY 1.446809 (-2575 3075);
PAINT GREEN (-2575 3075);
DISPLAY INVISIBLE (-2575 3075);
FORCEPROP 1 LAST HDL_TAP TRUE
J 0
(-2250 2900);
DISPLAY 1.446809 (-2250 2900);
PAINT GREEN (-2250 2900);
DISPLAY INVISIBLE (-2250 2900);
FORCEPROP 1 LAST PATH I115
J 0
(-2577 3025);
DISPLAY 0.872340 (-2577 3025);
PAINT GREEN (-2577 3025);
DISPLAY INVISIBLE (-2577 3025);
FORCEADD TAP..1
(-2575 1875);
FORCEPROP 3 LASTPIN (-2625 1875) SIG_NAME UPI_CPU1_CPU0_P0P0_DN<6>
J 0
(-2615 1885);
DISPLAY 0.659574 (-2615 1885);
PAINT MONO (-2615 1885);
DISPLAY INVISIBLE (-2615 1885);
FORCEPROP 1 LASTPIN (-2625 1875) BN 6
J 0
(-2637 1883);
DISPLAY 0.617021 (-2637 1883);
PAINT GREEN (-2637 1883);
FORCEPROP 2 LAST CDS_LIB mstr_standard
J 0
(-2575 1875);
PAINT MONO (-2575 1875);
DISPLAY INVISIBLE (-2575 1875);
FORCEPROP 1 LAST BODY_TYPE PLUMBING
J 0
(-2575 1925);
DISPLAY 1.446809 (-2575 1925);
PAINT GREEN (-2575 1925);
DISPLAY INVISIBLE (-2575 1925);
FORCEPROP 1 LAST HDL_TAP TRUE
J 0
(-2250 1750);
DISPLAY 1.446809 (-2250 1750);
PAINT GREEN (-2250 1750);
DISPLAY INVISIBLE (-2250 1750);
FORCEPROP 1 LAST PATH I116
J 0
(-2577 1875);
DISPLAY 0.872340 (-2577 1875);
PAINT GREEN (-2577 1875);
DISPLAY INVISIBLE (-2577 1875);
FORCEADD TAP..1
(-2575 1775);
FORCEPROP 3 LASTPIN (-2625 1775) SIG_NAME UPI_CPU1_CPU0_P0P0_DN<4>
J 0
(-2615 1785);
DISPLAY 0.659574 (-2615 1785);
PAINT MONO (-2615 1785);
DISPLAY INVISIBLE (-2615 1785);
FORCEPROP 1 LASTPIN (-2625 1775) BN 4
J 0
(-2637 1783);
DISPLAY 0.617021 (-2637 1783);
PAINT GREEN (-2637 1783);
FORCEPROP 2 LAST CDS_LIB mstr_standard
J 0
(-2575 1775);
PAINT MONO (-2575 1775);
DISPLAY INVISIBLE (-2575 1775);
FORCEPROP 1 LAST BODY_TYPE PLUMBING
J 0
(-2575 1825);
DISPLAY 1.446809 (-2575 1825);
PAINT GREEN (-2575 1825);
DISPLAY INVISIBLE (-2575 1825);
FORCEPROP 1 LAST HDL_TAP TRUE
J 0
(-2250 1650);
DISPLAY 1.446809 (-2250 1650);
PAINT GREEN (-2250 1650);
DISPLAY INVISIBLE (-2250 1650);
FORCEPROP 1 LAST PATH I117
J 0
(-2577 1775);
DISPLAY 0.872340 (-2577 1775);
PAINT GREEN (-2577 1775);
DISPLAY INVISIBLE (-2577 1775);
FORCEADD TAP..1
(-2575 2675);
FORCEPROP 3 LASTPIN (-2625 2675) SIG_NAME UPI_CPU1_CPU0_P0P0_DN<1>
J 0
(-2615 2685);
DISPLAY 0.659574 (-2615 2685);
PAINT MONO (-2615 2685);
DISPLAY INVISIBLE (-2615 2685);
FORCEPROP 1 LASTPIN (-2625 2675) BN 1
J 0
(-2637 2683);
DISPLAY 0.617021 (-2637 2683);
PAINT GREEN (-2637 2683);
FORCEPROP 2 LAST CDS_LIB mstr_standard
J 0
(-2575 2675);
PAINT MONO (-2575 2675);
DISPLAY INVISIBLE (-2575 2675);
FORCEPROP 1 LAST BODY_TYPE PLUMBING
J 0
(-2575 2725);
DISPLAY 1.446809 (-2575 2725);
PAINT GREEN (-2575 2725);
DISPLAY INVISIBLE (-2575 2725);
FORCEPROP 1 LAST HDL_TAP TRUE
J 0
(-2250 2550);
DISPLAY 1.446809 (-2250 2550);
PAINT GREEN (-2250 2550);
DISPLAY INVISIBLE (-2250 2550);
FORCEPROP 1 LAST PATH I118
J 0
(-2577 2675);
DISPLAY 0.872340 (-2577 2675);
PAINT GREEN (-2577 2675);
DISPLAY INVISIBLE (-2577 2675);
FORCEADD TAP..1
(-2575 2625);
FORCEPROP 3 LASTPIN (-2625 2625) SIG_NAME UPI_CPU1_CPU0_P0P0_DN<0>
J 0
(-2615 2635);
DISPLAY 0.659574 (-2615 2635);
PAINT MONO (-2615 2635);
DISPLAY INVISIBLE (-2615 2635);
FORCEPROP 1 LASTPIN (-2625 2625) BN 0
J 0
(-2637 2633);
DISPLAY 0.617021 (-2637 2633);
PAINT GREEN (-2637 2633);
FORCEPROP 2 LAST CDS_LIB mstr_standard
J 0
(-2575 2625);
PAINT MONO (-2575 2625);
DISPLAY INVISIBLE (-2575 2625);
FORCEPROP 1 LAST BODY_TYPE PLUMBING
J 0
(-2575 2675);
DISPLAY 1.446809 (-2575 2675);
PAINT GREEN (-2575 2675);
DISPLAY INVISIBLE (-2575 2675);
FORCEPROP 1 LAST HDL_TAP TRUE
J 0
(-2250 2500);
DISPLAY 1.446809 (-2250 2500);
PAINT GREEN (-2250 2500);
DISPLAY INVISIBLE (-2250 2500);
FORCEPROP 1 LAST PATH I119
J 0
(-2577 2625);
DISPLAY 0.872340 (-2577 2625);
PAINT GREEN (-2577 2625);
DISPLAY INVISIBLE (-2577 2625);
FORCEADD TAP..1
(-2900 2525);
FORCEPROP 3 LASTPIN (-2950 2525) SIG_NAME UPI_CPU1_CPU0_P0P0_DP<19>
J 0
(-2940 2535);
DISPLAY 0.659574 (-2940 2535);
PAINT MONO (-2940 2535);
DISPLAY INVISIBLE (-2940 2535);
FORCEPROP 1 LASTPIN (-2950 2525) BN 19
J 0
(-2962 2533);
DISPLAY 0.617021 (-2962 2533);
PAINT GREEN (-2962 2533);
FORCEPROP 2 LAST CDS_LIB mstr_standard
J 0
(-2900 2525);
PAINT MONO (-2900 2525);
DISPLAY INVISIBLE (-2900 2525);
FORCEPROP 1 LAST BODY_TYPE PLUMBING
J 0
(-2900 2575);
DISPLAY 1.446809 (-2900 2575);
PAINT GREEN (-2900 2575);
DISPLAY INVISIBLE (-2900 2575);
FORCEPROP 1 LAST HDL_TAP TRUE
J 0
(-2575 2400);
DISPLAY 1.446809 (-2575 2400);
PAINT GREEN (-2575 2400);
DISPLAY INVISIBLE (-2575 2400);
FORCEPROP 1 LAST PATH I120
J 0
(-2902 2525);
DISPLAY 0.872340 (-2902 2525);
PAINT GREEN (-2902 2525);
DISPLAY INVISIBLE (-2902 2525);
FORCEADD TAP..1
(-2900 2375);
FORCEPROP 3 LASTPIN (-2950 2375) SIG_NAME UPI_CPU1_CPU0_P0P0_DP<16>
J 0
(-2940 2385);
DISPLAY 0.659574 (-2940 2385);
PAINT MONO (-2940 2385);
DISPLAY INVISIBLE (-2940 2385);
FORCEPROP 1 LASTPIN (-2950 2375) BN 16
J 0
(-2962 2383);
DISPLAY 0.617021 (-2962 2383);
PAINT GREEN (-2962 2383);
FORCEPROP 2 LAST CDS_LIB mstr_standard
J 0
(-2900 2375);
PAINT MONO (-2900 2375);
DISPLAY INVISIBLE (-2900 2375);
FORCEPROP 1 LAST BODY_TYPE PLUMBING
J 0
(-2900 2425);
DISPLAY 1.446809 (-2900 2425);
PAINT GREEN (-2900 2425);
DISPLAY INVISIBLE (-2900 2425);
FORCEPROP 1 LAST HDL_TAP TRUE
J 0
(-2575 2250);
DISPLAY 1.446809 (-2575 2250);
PAINT GREEN (-2575 2250);
DISPLAY INVISIBLE (-2575 2250);
FORCEPROP 1 LAST PATH I121
J 0
(-2902 2375);
DISPLAY 0.872340 (-2902 2375);
PAINT GREEN (-2902 2375);
DISPLAY INVISIBLE (-2902 2375);
FORCEADD TAP..1
(-2900 2325);
FORCEPROP 3 LASTPIN (-2950 2325) SIG_NAME UPI_CPU1_CPU0_P0P0_DP<15>
J 0
(-2940 2335);
DISPLAY 0.659574 (-2940 2335);
PAINT MONO (-2940 2335);
DISPLAY INVISIBLE (-2940 2335);
FORCEPROP 1 LASTPIN (-2950 2325) BN 15
J 0
(-2962 2333);
DISPLAY 0.617021 (-2962 2333);
PAINT GREEN (-2962 2333);
FORCEPROP 2 LAST CDS_LIB mstr_standard
J 0
(-2900 2325);
PAINT MONO (-2900 2325);
DISPLAY INVISIBLE (-2900 2325);
FORCEPROP 1 LAST BODY_TYPE PLUMBING
J 0
(-2900 2375);
DISPLAY 1.446809 (-2900 2375);
PAINT GREEN (-2900 2375);
DISPLAY INVISIBLE (-2900 2375);
FORCEPROP 1 LAST HDL_TAP TRUE
J 0
(-2575 2200);
DISPLAY 1.446809 (-2575 2200);
PAINT GREEN (-2575 2200);
DISPLAY INVISIBLE (-2575 2200);
FORCEPROP 1 LAST PATH I122
J 0
(-2902 2325);
DISPLAY 0.872340 (-2902 2325);
PAINT GREEN (-2902 2325);
DISPLAY INVISIBLE (-2902 2325);
FORCEADD TAP..1
(-2900 2225);
FORCEPROP 3 LASTPIN (-2950 2225) SIG_NAME UPI_CPU1_CPU0_P0P0_DP<13>
J 0
(-2940 2235);
DISPLAY 0.659574 (-2940 2235);
PAINT MONO (-2940 2235);
DISPLAY INVISIBLE (-2940 2235);
FORCEPROP 1 LASTPIN (-2950 2225) BN 13
J 0
(-2962 2233);
DISPLAY 0.617021 (-2962 2233);
PAINT GREEN (-2962 2233);
FORCEPROP 2 LAST CDS_LIB mstr_standard
J 0
(-2900 2225);
PAINT MONO (-2900 2225);
DISPLAY INVISIBLE (-2900 2225);
FORCEPROP 1 LAST BODY_TYPE PLUMBING
J 0
(-2900 2275);
DISPLAY 1.446809 (-2900 2275);
PAINT GREEN (-2900 2275);
DISPLAY INVISIBLE (-2900 2275);
FORCEPROP 1 LAST HDL_TAP TRUE
J 0
(-2575 2100);
DISPLAY 1.446809 (-2575 2100);
PAINT GREEN (-2575 2100);
DISPLAY INVISIBLE (-2575 2100);
FORCEPROP 1 LAST PATH I123
J 0
(-2902 2225);
DISPLAY 0.872340 (-2902 2225);
PAINT GREEN (-2902 2225);
DISPLAY INVISIBLE (-2902 2225);
FORCEADD TAP..1
(-2900 2175);
FORCEPROP 3 LASTPIN (-2950 2175) SIG_NAME UPI_CPU1_CPU0_P0P0_DP<12>
J 0
(-2940 2185);
DISPLAY 0.659574 (-2940 2185);
PAINT MONO (-2940 2185);
DISPLAY INVISIBLE (-2940 2185);
FORCEPROP 1 LASTPIN (-2950 2175) BN 12
J 0
(-2962 2183);
DISPLAY 0.617021 (-2962 2183);
PAINT GREEN (-2962 2183);
FORCEPROP 2 LAST CDS_LIB mstr_standard
J 0
(-2900 2175);
PAINT MONO (-2900 2175);
DISPLAY INVISIBLE (-2900 2175);
FORCEPROP 1 LAST BODY_TYPE PLUMBING
J 0
(-2900 2225);
DISPLAY 1.446809 (-2900 2225);
PAINT GREEN (-2900 2225);
DISPLAY INVISIBLE (-2900 2225);
FORCEPROP 1 LAST HDL_TAP TRUE
J 0
(-2575 2050);
DISPLAY 1.446809 (-2575 2050);
PAINT GREEN (-2575 2050);
DISPLAY INVISIBLE (-2575 2050);
FORCEPROP 1 LAST PATH I124
J 0
(-2902 2175);
DISPLAY 0.872340 (-2902 2175);
PAINT GREEN (-2902 2175);
DISPLAY INVISIBLE (-2902 2175);
FORCEADD TAP..1
(-2900 2125);
FORCEPROP 3 LASTPIN (-2950 2125) SIG_NAME UPI_CPU1_CPU0_P0P0_DP<11>
J 0
(-2940 2135);
DISPLAY 0.659574 (-2940 2135);
PAINT MONO (-2940 2135);
DISPLAY INVISIBLE (-2940 2135);
FORCEPROP 1 LASTPIN (-2950 2125) BN 11
J 0
(-2962 2133);
DISPLAY 0.617021 (-2962 2133);
PAINT GREEN (-2962 2133);
FORCEPROP 2 LAST CDS_LIB mstr_standard
J 0
(-2900 2125);
PAINT MONO (-2900 2125);
DISPLAY INVISIBLE (-2900 2125);
FORCEPROP 1 LAST BODY_TYPE PLUMBING
J 0
(-2900 2175);
DISPLAY 1.446809 (-2900 2175);
PAINT GREEN (-2900 2175);
DISPLAY INVISIBLE (-2900 2175);
FORCEPROP 1 LAST HDL_TAP TRUE
J 0
(-2575 2000);
DISPLAY 1.446809 (-2575 2000);
PAINT GREEN (-2575 2000);
DISPLAY INVISIBLE (-2575 2000);
FORCEPROP 1 LAST PATH I125
J 0
(-2902 2125);
DISPLAY 0.872340 (-2902 2125);
PAINT GREEN (-2902 2125);
DISPLAY INVISIBLE (-2902 2125);
FORCEADD TAP..1
(-2900 1975);
FORCEPROP 3 LASTPIN (-2950 1975) SIG_NAME UPI_CPU1_CPU0_P0P0_DP<8>
J 0
(-2940 1985);
DISPLAY 0.659574 (-2940 1985);
PAINT MONO (-2940 1985);
DISPLAY INVISIBLE (-2940 1985);
FORCEPROP 1 LASTPIN (-2950 1975) BN 8
J 0
(-2962 1983);
DISPLAY 0.617021 (-2962 1983);
PAINT GREEN (-2962 1983);
FORCEPROP 2 LAST CDS_LIB mstr_standard
J 0
(-2900 1975);
PAINT MONO (-2900 1975);
DISPLAY INVISIBLE (-2900 1975);
FORCEPROP 1 LAST BODY_TYPE PLUMBING
J 0
(-2900 2025);
DISPLAY 1.446809 (-2900 2025);
PAINT GREEN (-2900 2025);
DISPLAY INVISIBLE (-2900 2025);
FORCEPROP 1 LAST HDL_TAP TRUE
J 0
(-2575 1850);
DISPLAY 1.446809 (-2575 1850);
PAINT GREEN (-2575 1850);
DISPLAY INVISIBLE (-2575 1850);
FORCEPROP 1 LAST PATH I126
J 0
(-2902 1975);
DISPLAY 0.872340 (-2902 1975);
PAINT GREEN (-2902 1975);
DISPLAY INVISIBLE (-2902 1975);
FORCEADD TAP..1
(-2900 2925);
FORCEPROP 3 LASTPIN (-2950 2925) SIG_NAME UPI_CPU1_CPU0_P0P0_DP<6>
J 0
(-2940 2935);
DISPLAY 0.659574 (-2940 2935);
PAINT MONO (-2940 2935);
DISPLAY INVISIBLE (-2940 2935);
FORCEPROP 1 LASTPIN (-2950 2925) BN 6
J 0
(-2962 2933);
DISPLAY 0.617021 (-2962 2933);
PAINT GREEN (-2962 2933);
FORCEPROP 2 LAST CDS_LIB mstr_standard
J 0
(-2900 2925);
PAINT MONO (-2900 2925);
DISPLAY INVISIBLE (-2900 2925);
FORCEPROP 1 LAST BODY_TYPE PLUMBING
J 0
(-2900 2975);
DISPLAY 1.446809 (-2900 2975);
PAINT GREEN (-2900 2975);
DISPLAY INVISIBLE (-2900 2975);
FORCEPROP 1 LAST HDL_TAP TRUE
J 0
(-2575 2800);
DISPLAY 1.446809 (-2575 2800);
PAINT GREEN (-2575 2800);
DISPLAY INVISIBLE (-2575 2800);
FORCEPROP 1 LAST PATH I127
J 0
(-2902 2925);
DISPLAY 0.872340 (-2902 2925);
PAINT GREEN (-2902 2925);
DISPLAY INVISIBLE (-2902 2925);
FORCEADD TAP..1
(-2900 2825);
FORCEPROP 3 LASTPIN (-2950 2825) SIG_NAME UPI_CPU1_CPU0_P0P0_DP<4>
J 0
(-2940 2835);
DISPLAY 0.659574 (-2940 2835);
PAINT MONO (-2940 2835);
DISPLAY INVISIBLE (-2940 2835);
FORCEPROP 1 LASTPIN (-2950 2825) BN 4
J 0
(-2962 2833);
DISPLAY 0.617021 (-2962 2833);
PAINT GREEN (-2962 2833);
FORCEPROP 2 LAST CDS_LIB mstr_standard
J 0
(-2900 2825);
PAINT MONO (-2900 2825);
DISPLAY INVISIBLE (-2900 2825);
FORCEPROP 1 LAST BODY_TYPE PLUMBING
J 0
(-2900 2875);
DISPLAY 1.446809 (-2900 2875);
PAINT GREEN (-2900 2875);
DISPLAY INVISIBLE (-2900 2875);
FORCEPROP 1 LAST HDL_TAP TRUE
J 0
(-2575 2700);
DISPLAY 1.446809 (-2575 2700);
PAINT GREEN (-2575 2700);
DISPLAY INVISIBLE (-2575 2700);
FORCEPROP 1 LAST PATH I128
J 0
(-2902 2825);
DISPLAY 0.872340 (-2902 2825);
PAINT GREEN (-2902 2825);
DISPLAY INVISIBLE (-2902 2825);
FORCEADD TAP..1
(-2900 1625);
FORCEPROP 3 LASTPIN (-2950 1625) SIG_NAME UPI_CPU1_CPU0_P0P0_DP<1>
J 0
(-2940 1635);
DISPLAY 0.659574 (-2940 1635);
PAINT MONO (-2940 1635);
DISPLAY INVISIBLE (-2940 1635);
FORCEPROP 1 LASTPIN (-2950 1625) BN 1
J 0
(-2962 1633);
DISPLAY 0.617021 (-2962 1633);
PAINT GREEN (-2962 1633);
FORCEPROP 2 LAST CDS_LIB mstr_standard
J 0
(-2900 1625);
PAINT MONO (-2900 1625);
DISPLAY INVISIBLE (-2900 1625);
FORCEPROP 1 LAST BODY_TYPE PLUMBING
J 0
(-2900 1675);
DISPLAY 1.446809 (-2900 1675);
PAINT GREEN (-2900 1675);
DISPLAY INVISIBLE (-2900 1675);
FORCEPROP 1 LAST HDL_TAP TRUE
J 0
(-2575 1500);
DISPLAY 1.446809 (-2575 1500);
PAINT GREEN (-2575 1500);
DISPLAY INVISIBLE (-2575 1500);
FORCEPROP 1 LAST PATH I129
J 0
(-2902 1625);
DISPLAY 0.872340 (-2902 1625);
PAINT GREEN (-2902 1625);
DISPLAY INVISIBLE (-2902 1625);
FORCEADD TAP..1
(-2900 1575);
FORCEPROP 3 LASTPIN (-2950 1575) SIG_NAME UPI_CPU1_CPU0_P0P0_DP<0>
J 0
(-2940 1585);
DISPLAY 0.659574 (-2940 1585);
PAINT MONO (-2940 1585);
DISPLAY INVISIBLE (-2940 1585);
FORCEPROP 1 LASTPIN (-2950 1575) BN 0
J 0
(-2962 1583);
DISPLAY 0.617021 (-2962 1583);
PAINT GREEN (-2962 1583);
FORCEPROP 2 LAST CDS_LIB mstr_standard
J 0
(-2900 1575);
PAINT MONO (-2900 1575);
DISPLAY INVISIBLE (-2900 1575);
FORCEPROP 1 LAST BODY_TYPE PLUMBING
J 0
(-2900 1625);
DISPLAY 1.446809 (-2900 1625);
PAINT GREEN (-2900 1625);
DISPLAY INVISIBLE (-2900 1625);
FORCEPROP 1 LAST HDL_TAP TRUE
J 0
(-2575 1450);
DISPLAY 1.446809 (-2575 1450);
PAINT GREEN (-2575 1450);
DISPLAY INVISIBLE (-2575 1450);
FORCEPROP 1 LAST PATH I130
J 0
(-2902 1575);
DISPLAY 0.872340 (-2902 1575);
PAINT GREEN (-2902 1575);
DISPLAY INVISIBLE (-2902 1575);
FORCEADD TAP..1
R 2
(-5500 1625);
FORCEPROP 3 LASTPIN (-5450 1625) SIG_NAME UPI_CPU0_CPU1_P0P0_DN<1>
J 0
(-5440 1635);
DISPLAY 0.659574 (-5440 1635);
PAINT MONO (-5440 1635);
DISPLAY INVISIBLE (-5440 1635);
FORCEPROP 1 LASTPIN (-5450 1625) BN 1
J 2
(-5438 1633);
DISPLAY 0.617021 (-5438 1633);
PAINT GREEN (-5438 1633);
FORCEPROP 2 LAST CDS_LIB mstr_standard
J 0
(-5500 1625);
PAINT MONO (-5500 1625);
DISPLAY INVISIBLE (-5500 1625);
FORCEPROP 1 LAST BODY_TYPE PLUMBING
J 2
(-5500 1675);
DISPLAY 1.446809 (-5500 1675);
PAINT GREEN (-5500 1675);
DISPLAY INVISIBLE (-5500 1675);
FORCEPROP 1 LAST HDL_TAP TRUE
J 2
(-5825 1500);
DISPLAY 1.446809 (-5825 1500);
PAINT GREEN (-5825 1500);
DISPLAY INVISIBLE (-5825 1500);
FORCEPROP 1 LAST PATH I131
J 2
(-5498 1625);
DISPLAY 0.872340 (-5498 1625);
PAINT GREEN (-5498 1625);
DISPLAY INVISIBLE (-5498 1625);
FORCEADD SKX_EXT_B..13
(-4050 2575);
FORCEPROP 1 LAST LOCATION U2D1
J 0
(-4800 3825);
DISPLAY 0.617021 (-4800 3825);
PAINT AQUA (-4800 3825);
FORCEPROP 1 LAST PART_NUMBER TBD
J 0
(-4800 1375);
DISPLAY 0.617021 (-4800 1375);
PAINT BLUE (-4800 1375);
FORCEPROP 1 LAST MATERIAL IC
J 0
(-4800 3775);
DISPLAY 0.617021 (-4800 3775);
PAINT SKYBLUE (-4800 3775);
FORCEPROP 2 LASTPIN (-3250 3575) $PN BH3
J 0
(-3240 3585);
DISPLAY 0.617021 (-3240 3585);
PAINT ORANGE (-3240 3585);
FORCEPROP 2 LASTPIN (-3250 3525) $PN BD3
J 0
(-3240 3535);
DISPLAY 0.617021 (-3240 3535);
PAINT ORANGE (-3240 3535);
FORCEPROP 2 LASTPIN (-3250 3475) $PN BC2
J 0
(-3240 3485);
DISPLAY 0.617021 (-3240 3485);
PAINT ORANGE (-3240 3485);
FORCEPROP 2 LASTPIN (-3250 3425) $PN AY3
J 0
(-3240 3435);
DISPLAY 0.617021 (-3240 3435);
PAINT ORANGE (-3240 3435);
FORCEPROP 2 LASTPIN (-3250 3375) $PN AW4
J 0
(-3240 3385);
DISPLAY 0.617021 (-3240 3385);
PAINT ORANGE (-3240 3385);
FORCEPROP 2 LASTPIN (-3250 3325) $PN AR4
J 0
(-3240 3335);
DISPLAY 0.617021 (-3240 3335);
PAINT ORANGE (-3240 3335);
FORCEPROP 2 LASTPIN (-3250 3275) $PN AR2
J 0
(-3240 3285);
DISPLAY 0.617021 (-3240 3285);
PAINT ORANGE (-3240 3285);
FORCEPROP 2 LASTPIN (-3250 3225) $PN AP1
J 0
(-3240 3235);
DISPLAY 0.617021 (-3240 3235);
PAINT ORANGE (-3240 3235);
FORCEPROP 2 LASTPIN (-3250 3175) $PN AP3
J 0
(-3240 3185);
DISPLAY 0.617021 (-3240 3185);
PAINT ORANGE (-3240 3185);
FORCEPROP 2 LASTPIN (-3250 3125) $PN AK3
J 0
(-3240 3135);
DISPLAY 0.617021 (-3240 3135);
PAINT ORANGE (-3240 3135);
FORCEPROP 2 LASTPIN (-3250 3075) $PN AK1
J 0
(-3240 3085);
DISPLAY 0.617021 (-3240 3085);
PAINT ORANGE (-3240 3085);
FORCEPROP 2 LASTPIN (-3250 3025) $PN AJ2
J 0
(-3240 3035);
DISPLAY 0.617021 (-3240 3035);
PAINT ORANGE (-3240 3035);
FORCEPROP 2 LASTPIN (-3250 2975) $PN AG2
J 0
(-3240 2985);
DISPLAY 0.617021 (-3240 2985);
PAINT ORANGE (-3240 2985);
FORCEPROP 2 LASTPIN (-3250 2925) $PN AF3
J 0
(-3240 2935);
DISPLAY 0.617021 (-3240 2935);
PAINT ORANGE (-3240 2935);
FORCEPROP 2 LASTPIN (-3250 2875) $PN AD1
J 0
(-3240 2885);
DISPLAY 0.617021 (-3240 2885);
PAINT ORANGE (-3240 2885);
FORCEPROP 2 LASTPIN (-3250 2825) $PN AA2
J 0
(-3240 2835);
DISPLAY 0.617021 (-3240 2835);
PAINT ORANGE (-3240 2835);
FORCEPROP 2 LASTPIN (-3250 2775) $PN W2
J 0
(-3240 2785);
DISPLAY 0.617021 (-3240 2785);
PAINT ORANGE (-3240 2785);
FORCEPROP 2 LASTPIN (-3250 2725) $PN Y3
J 0
(-3240 2735);
DISPLAY 0.617021 (-3240 2735);
PAINT ORANGE (-3240 2735);
FORCEPROP 2 LASTPIN (-3250 2675) $PN T1
J 0
(-3240 2685);
DISPLAY 0.617021 (-3240 2685);
PAINT ORANGE (-3240 2685);
FORCEPROP 2 LASTPIN (-3250 2625) $PN M1
J 0
(-3240 2635);
DISPLAY 0.617021 (-3240 2635);
PAINT ORANGE (-3240 2635);
FORCEPROP 2 LASTPIN (-3250 2525) $PN BG4
J 0
(-3240 2535);
DISPLAY 0.617021 (-3240 2535);
PAINT ORANGE (-3240 2535);
FORCEPROP 2 LASTPIN (-3250 2475) $PN BF3
J 0
(-3240 2485);
DISPLAY 0.617021 (-3240 2485);
PAINT ORANGE (-3240 2485);
FORCEPROP 2 LASTPIN (-3250 2425) $PN BB3
J 0
(-3240 2435);
DISPLAY 0.617021 (-3240 2435);
PAINT ORANGE (-3240 2435);
FORCEPROP 2 LASTPIN (-3250 2375) $PN BA4
J 0
(-3240 2385);
DISPLAY 0.617021 (-3240 2385);
PAINT ORANGE (-3240 2385);
FORCEPROP 2 LASTPIN (-3250 2325) $PN AV5
J 0
(-3240 2335);
DISPLAY 0.617021 (-3240 2335);
PAINT ORANGE (-3240 2335);
FORCEPROP 2 LASTPIN (-3250 2275) $PN AU4
J 0
(-3240 2285);
DISPLAY 0.617021 (-3240 2285);
PAINT ORANGE (-3240 2285);
FORCEPROP 2 LASTPIN (-3250 2225) $PN AT3
J 0
(-3240 2235);
DISPLAY 0.617021 (-3240 2235);
PAINT ORANGE (-3240 2235);
FORCEPROP 2 LASTPIN (-3250 2175) $PN AT1
J 0
(-3240 2185);
DISPLAY 0.617021 (-3240 2185);
PAINT ORANGE (-3240 2185);
FORCEPROP 2 LASTPIN (-3250 2125) $PN AN4
J 0
(-3240 2135);
DISPLAY 0.617021 (-3240 2135);
PAINT ORANGE (-3240 2135);
FORCEPROP 2 LASTPIN (-3250 2075) $PN AM3
J 0
(-3240 2085);
DISPLAY 0.617021 (-3240 2085);
PAINT ORANGE (-3240 2085);
FORCEPROP 2 LASTPIN (-3250 2025) $PN AL2
J 0
(-3240 2035);
DISPLAY 0.617021 (-3240 2035);
PAINT ORANGE (-3240 2035);
FORCEPROP 2 LASTPIN (-3250 1975) $PN AH3
J 0
(-3240 1985);
DISPLAY 0.617021 (-3240 1985);
PAINT ORANGE (-3240 1985);
FORCEPROP 2 LASTPIN (-3250 1925) $PN AE2
J 0
(-3240 1935);
DISPLAY 0.617021 (-3240 1935);
PAINT ORANGE (-3240 1935);
FORCEPROP 2 LASTPIN (-3250 1875) $PN AG4
J 0
(-3240 1885);
DISPLAY 0.617021 (-3240 1885);
PAINT ORANGE (-3240 1885);
FORCEPROP 2 LASTPIN (-3250 1825) $PN AC2
J 0
(-3240 1835);
DISPLAY 0.617021 (-3240 1835);
PAINT ORANGE (-3240 1835);
FORCEPROP 2 LASTPIN (-3250 1775) $PN AB3
J 0
(-3240 1785);
DISPLAY 0.617021 (-3240 1785);
PAINT ORANGE (-3240 1785);
FORCEPROP 2 LASTPIN (-3250 1725) $PN Y1
J 0
(-3240 1735);
DISPLAY 0.617021 (-3240 1735);
PAINT ORANGE (-3240 1735);
FORCEPROP 2 LASTPIN (-3250 1675) $PN V3
J 0
(-3240 1685);
DISPLAY 0.617021 (-3240 1685);
PAINT ORANGE (-3240 1685);
FORCEPROP 2 LASTPIN (-3250 1625) $PN P1
J 0
(-3240 1635);
DISPLAY 0.617021 (-3240 1635);
PAINT ORANGE (-3240 1635);
FORCEPROP 2 LASTPIN (-3250 1575) $PN N2
J 0
(-3240 1585);
DISPLAY 0.617021 (-3240 1585);
PAINT ORANGE (-3240 1585);
FORCEPROP 2 LASTPIN (-4850 3575) $PN BA10
J 2
(-4860 3585);
DISPLAY 0.617021 (-4860 3585);
PAINT ORANGE (-4860 3585);
FORCEPROP 2 LASTPIN (-4850 3525) $PN BC10
J 2
(-4860 3535);
DISPLAY 0.617021 (-4860 3535);
PAINT ORANGE (-4860 3535);
FORCEPROP 2 LASTPIN (-4850 3475) $PN BB9
J 2
(-4860 3485);
DISPLAY 0.617021 (-4860 3485);
PAINT ORANGE (-4860 3485);
FORCEPROP 2 LASTPIN (-4850 3425) $PN AV9
J 2
(-4860 3435);
DISPLAY 0.617021 (-4860 3435);
PAINT ORANGE (-4860 3435);
FORCEPROP 2 LASTPIN (-4850 3375) $PN BF7
J 2
(-4860 3385);
DISPLAY 0.617021 (-4860 3385);
PAINT ORANGE (-4860 3385);
FORCEPROP 2 LASTPIN (-4850 3325) $PN BB7
J 2
(-4860 3335);
DISPLAY 0.617021 (-4860 3335);
PAINT ORANGE (-4860 3335);
FORCEPROP 2 LASTPIN (-4850 3275) $PN AY7
J 2
(-4860 3285);
DISPLAY 0.617021 (-4860 3285);
PAINT ORANGE (-4860 3285);
FORCEPROP 2 LASTPIN (-4850 3225) $PN AT9
J 2
(-4860 3235);
DISPLAY 0.617021 (-4860 3235);
PAINT ORANGE (-4860 3235);
FORCEPROP 2 LASTPIN (-4850 3175) $PN AU8
J 2
(-4860 3185);
DISPLAY 0.617021 (-4860 3185);
PAINT ORANGE (-4860 3185);
FORCEPROP 2 LASTPIN (-4850 3125) $PN AN8
J 2
(-4860 3135);
DISPLAY 0.617021 (-4860 3135);
PAINT ORANGE (-4860 3135);
FORCEPROP 2 LASTPIN (-4850 3075) $PN AL8
J 2
(-4860 3085);
DISPLAY 0.617021 (-4860 3085);
PAINT ORANGE (-4860 3085);
FORCEPROP 2 LASTPIN (-4850 3025) $PN AM7
J 2
(-4860 3035);
DISPLAY 0.617021 (-4860 3035);
PAINT ORANGE (-4860 3035);
FORCEPROP 2 LASTPIN (-4850 2975) $PN AK5
J 2
(-4860 2985);
DISPLAY 0.617021 (-4860 2985);
PAINT ORANGE (-4860 2985);
FORCEPROP 2 LASTPIN (-4850 2925) $PN AH7
J 2
(-4860 2935);
DISPLAY 0.617021 (-4860 2935);
PAINT ORANGE (-4860 2935);
FORCEPROP 2 LASTPIN (-4850 2875) $PN AF7
J 2
(-4860 2885);
DISPLAY 0.617021 (-4860 2885);
PAINT ORANGE (-4860 2885);
FORCEPROP 2 LASTPIN (-4850 2825) $PN AG6
J 2
(-4860 2835);
DISPLAY 0.617021 (-4860 2835);
PAINT ORANGE (-4860 2835);
FORCEPROP 2 LASTPIN (-4850 2775) $PN AC6
J 2
(-4860 2785);
DISPLAY 0.617021 (-4860 2785);
PAINT ORANGE (-4860 2785);
FORCEPROP 2 LASTPIN (-4850 2725) $PN AA6
J 2
(-4860 2735);
DISPLAY 0.617021 (-4860 2735);
PAINT ORANGE (-4860 2735);
FORCEPROP 2 LASTPIN (-4850 2675) $PN AC8
J 2
(-4860 2685);
DISPLAY 0.617021 (-4860 2685);
PAINT ORANGE (-4860 2685);
FORCEPROP 2 LASTPIN (-4850 2625) $PN AB9
J 2
(-4860 2635);
DISPLAY 0.617021 (-4860 2635);
PAINT ORANGE (-4860 2635);
FORCEPROP 2 LASTPIN (-4850 2525) $PN BB11
J 2
(-4860 2535);
DISPLAY 0.617021 (-4860 2535);
PAINT ORANGE (-4860 2535);
FORCEPROP 2 LASTPIN (-4850 2475) $PN BD9
J 2
(-4860 2485);
DISPLAY 0.617021 (-4860 2485);
PAINT ORANGE (-4860 2485);
FORCEPROP 2 LASTPIN (-4850 2425) $PN AY9
J 2
(-4860 2435);
DISPLAY 0.617021 (-4860 2435);
PAINT ORANGE (-4860 2435);
FORCEPROP 2 LASTPIN (-4850 2375) $PN AW8
J 2
(-4860 2385);
DISPLAY 0.617021 (-4860 2385);
PAINT ORANGE (-4860 2385);
FORCEPROP 2 LASTPIN (-4850 2325) $PN BD7
J 2
(-4860 2335);
DISPLAY 0.617021 (-4860 2335);
PAINT ORANGE (-4860 2335);
FORCEPROP 2 LASTPIN (-4850 2275) $PN BC6
J 2
(-4860 2285);
DISPLAY 0.617021 (-4860 2285);
PAINT ORANGE (-4860 2285);
FORCEPROP 2 LASTPIN (-4850 2225) $PN BA8
J 2
(-4860 2235);
DISPLAY 0.617021 (-4860 2235);
PAINT ORANGE (-4860 2235);
FORCEPROP 2 LASTPIN (-4850 2175) $PN AU10
J 2
(-4860 2185);
DISPLAY 0.617021 (-4860 2185);
PAINT ORANGE (-4860 2185);
FORCEPROP 2 LASTPIN (-4850 2125) $PN AR8
J 2
(-4860 2135);
DISPLAY 0.617021 (-4860 2135);
PAINT ORANGE (-4860 2135);
FORCEPROP 2 LASTPIN (-4850 2075) $PN AP7
J 2
(-4860 2085);
DISPLAY 0.617021 (-4860 2085);
PAINT ORANGE (-4860 2085);
FORCEPROP 2 LASTPIN (-4850 2025) $PN AM9
J 2
(-4860 2035);
DISPLAY 0.617021 (-4860 2035);
PAINT ORANGE (-4860 2035);
FORCEPROP 2 LASTPIN (-4850 1975) $PN AK7
J 2
(-4860 1985);
DISPLAY 0.617021 (-4860 1985);
PAINT ORANGE (-4860 1985);
FORCEPROP 2 LASTPIN (-4850 1925) $PN AL6
J 2
(-4860 1935);
DISPLAY 0.617021 (-4860 1935);
PAINT ORANGE (-4860 1935);
FORCEPROP 2 LASTPIN (-4850 1875) $PN AJ6
J 2
(-4860 1885);
DISPLAY 0.617021 (-4860 1885);
PAINT ORANGE (-4860 1885);
FORCEPROP 2 LASTPIN (-4850 1825) $PN AG8
J 2
(-4860 1835);
DISPLAY 0.617021 (-4860 1835);
PAINT ORANGE (-4860 1835);
FORCEPROP 2 LASTPIN (-4850 1775) $PN AE6
J 2
(-4860 1785);
DISPLAY 0.617021 (-4860 1785);
PAINT ORANGE (-4860 1785);
FORCEPROP 2 LASTPIN (-4850 1725) $PN AD5
J 2
(-4860 1735);
DISPLAY 0.617021 (-4860 1735);
PAINT ORANGE (-4860 1735);
FORCEPROP 2 LASTPIN (-4850 1675) $PN AB7
J 2
(-4860 1685);
DISPLAY 0.617021 (-4860 1685);
PAINT ORANGE (-4860 1685);
FORCEPROP 2 LASTPIN (-4850 1625) $PN AA8
J 2
(-4860 1635);
DISPLAY 0.617021 (-4860 1635);
PAINT ORANGE (-4860 1635);
FORCEPROP 2 LASTPIN (-4850 1575) $PN AC10
J 2
(-4860 1585);
DISPLAY 0.617021 (-4860 1585);
PAINT ORANGE (-4860 1585);
FORCEPROP 1 LAST PACK_TYPE BGA1
J 0
(-4800 3875);
PAINT SKYBLUE (-4800 3875);
DISPLAY INVISIBLE (-4800 3875);
FORCEPROP 2 LAST SEC_TYPE BGA1
J 0
(-4800 3875);
DISPLAY 1.021277 (-4800 3875);
PAINT ORANGE (-4800 3875);
DISPLAY INVISIBLE (-4800 3875);
FORCEPROP 2 LAST CDS_LIB chpset_lib
J 0
(-4050 2575);
PAINT ORANGE (-4050 2575);
DISPLAY INVISIBLE (-4050 2575);
FORCEPROP 2 LAST SEC 13
J 0
(-4800 3875);
DISPLAY 0.680851 (-4800 3875);
PAINT MONO (-4800 3875);
DISPLAY INVISIBLE (-4800 3875);
FORCEPROP 2 LAST CDS_LOCATION U2D1
J 0
(-4800 3825);
DISPLAY 0.617021 (-4800 3825);
PAINT AQUA (-4800 3825);
DISPLAY INVISIBLE (-4800 3825);
FORCEPROP 1 LAST PATH I132
J 0
(-4050 3775);
PAINT GREEN (-4050 3775);
DISPLAY INVISIBLE (-4050 3775);
FORCEADD TAP..1
R 2
(-5500 2075);
FORCEPROP 3 LASTPIN (-5450 2075) SIG_NAME UPI_CPU0_CPU1_P0P0_DN<10>
J 0
(-5440 2085);
DISPLAY 0.659574 (-5440 2085);
PAINT MONO (-5440 2085);
DISPLAY INVISIBLE (-5440 2085);
FORCEPROP 1 LASTPIN (-5450 2075) BN 10
J 2
(-5438 2083);
DISPLAY 0.617021 (-5438 2083);
PAINT GREEN (-5438 2083);
FORCEPROP 2 LAST CDS_LIB mstr_standard
J 0
(-5500 2075);
PAINT MONO (-5500 2075);
DISPLAY INVISIBLE (-5500 2075);
FORCEPROP 1 LAST BODY_TYPE PLUMBING
J 2
(-5500 2125);
DISPLAY 1.446809 (-5500 2125);
PAINT GREEN (-5500 2125);
DISPLAY INVISIBLE (-5500 2125);
FORCEPROP 1 LAST HDL_TAP TRUE
J 2
(-5825 1950);
DISPLAY 1.446809 (-5825 1950);
PAINT GREEN (-5825 1950);
DISPLAY INVISIBLE (-5825 1950);
FORCEPROP 1 LAST PATH I14
J 2
(-5498 2075);
DISPLAY 0.872340 (-5498 2075);
PAINT GREEN (-5498 2075);
DISPLAY INVISIBLE (-5498 2075);
FORCEADD TAP..1
R 2
(-5500 2175);
FORCEPROP 3 LASTPIN (-5450 2175) SIG_NAME UPI_CPU0_CPU1_P0P0_DN<12>
J 0
(-5440 2185);
DISPLAY 0.659574 (-5440 2185);
PAINT MONO (-5440 2185);
DISPLAY INVISIBLE (-5440 2185);
FORCEPROP 1 LASTPIN (-5450 2175) BN 12
J 2
(-5438 2183);
DISPLAY 0.617021 (-5438 2183);
PAINT GREEN (-5438 2183);
FORCEPROP 2 LAST CDS_LIB mstr_standard
J 0
(-5500 2175);
PAINT MONO (-5500 2175);
DISPLAY INVISIBLE (-5500 2175);
FORCEPROP 1 LAST BODY_TYPE PLUMBING
J 2
(-5500 2225);
DISPLAY 1.446809 (-5500 2225);
PAINT GREEN (-5500 2225);
DISPLAY INVISIBLE (-5500 2225);
FORCEPROP 1 LAST HDL_TAP TRUE
J 2
(-5825 2050);
DISPLAY 1.446809 (-5825 2050);
PAINT GREEN (-5825 2050);
DISPLAY INVISIBLE (-5825 2050);
FORCEPROP 1 LAST PATH I16
J 2
(-5498 2175);
DISPLAY 0.872340 (-5498 2175);
PAINT GREEN (-5498 2175);
DISPLAY INVISIBLE (-5498 2175);
FORCEADD OFFPAGE..1
(-6700 3700);
FORCEPROP 2 LAST $XR0 33 
J 0
(-6951 3700);
DISPLAY 0.638298 (-6951 3700);
PAINT MONO (-6951 3700);
FORCEPROP 2 LAST CDS_LIB mstr_standard
J 0
(-6700 3700);
PAINT MONO (-6700 3700);
DISPLAY INVISIBLE (-6700 3700);
FORCEPROP 1 LAST OFFPAGE TRUE
J 0
(-6375 3575);
DISPLAY 1.170213 (-6375 3575);
PAINT GREEN (-6375 3575);
DISPLAY INVISIBLE (-6375 3575);
FORCEPROP 1 LAST COMMENT_BODY TRUE
J 0
(-6575 3600);
DISPLAY 1.170213 (-6575 3600);
PAINT GREEN (-6575 3600);
DISPLAY INVISIBLE (-6575 3600);
FORCEPROP 2 LAST PATH I2
J 0
(-6650 3775);
DISPLAY 1.021277 (-6650 3775);
PAINT ORANGE (-6650 3775);
DISPLAY INVISIBLE (-6650 3775);
FORCEADD TAP..1
R 2
(-5500 2375);
FORCEPROP 3 LASTPIN (-5450 2375) SIG_NAME UPI_CPU0_CPU1_P0P0_DN<16>
J 0
(-5440 2385);
DISPLAY 0.659574 (-5440 2385);
PAINT MONO (-5440 2385);
DISPLAY INVISIBLE (-5440 2385);
FORCEPROP 1 LASTPIN (-5450 2375) BN 16
J 2
(-5438 2383);
DISPLAY 0.617021 (-5438 2383);
PAINT GREEN (-5438 2383);
FORCEPROP 2 LAST CDS_LIB mstr_standard
J 0
(-5500 2375);
PAINT MONO (-5500 2375);
DISPLAY INVISIBLE (-5500 2375);
FORCEPROP 1 LAST BODY_TYPE PLUMBING
J 2
(-5500 2425);
DISPLAY 1.446809 (-5500 2425);
PAINT GREEN (-5500 2425);
DISPLAY INVISIBLE (-5500 2425);
FORCEPROP 1 LAST HDL_TAP TRUE
J 2
(-5825 2250);
DISPLAY 1.446809 (-5825 2250);
PAINT GREEN (-5825 2250);
DISPLAY INVISIBLE (-5825 2250);
FORCEPROP 1 LAST PATH I20
J 2
(-5498 2375);
DISPLAY 0.872340 (-5498 2375);
PAINT GREEN (-5498 2375);
DISPLAY INVISIBLE (-5498 2375);
FORCEADD TAP..1
R 2
(-5500 2425);
FORCEPROP 3 LASTPIN (-5450 2425) SIG_NAME UPI_CPU0_CPU1_P0P0_DN<17>
J 0
(-5440 2435);
DISPLAY 0.659574 (-5440 2435);
PAINT MONO (-5440 2435);
DISPLAY INVISIBLE (-5440 2435);
FORCEPROP 1 LASTPIN (-5450 2425) BN 17
J 2
(-5438 2433);
DISPLAY 0.617021 (-5438 2433);
PAINT GREEN (-5438 2433);
FORCEPROP 2 LAST CDS_LIB mstr_standard
J 0
(-5500 2425);
PAINT MONO (-5500 2425);
DISPLAY INVISIBLE (-5500 2425);
FORCEPROP 1 LAST BODY_TYPE PLUMBING
J 2
(-5500 2475);
DISPLAY 1.446809 (-5500 2475);
PAINT GREEN (-5500 2475);
DISPLAY INVISIBLE (-5500 2475);
FORCEPROP 1 LAST HDL_TAP TRUE
J 2
(-5825 2300);
DISPLAY 1.446809 (-5825 2300);
PAINT GREEN (-5825 2300);
DISPLAY INVISIBLE (-5825 2300);
FORCEPROP 1 LAST PATH I21
J 2
(-5498 2425);
DISPLAY 0.872340 (-5498 2425);
PAINT GREEN (-5498 2425);
DISPLAY INVISIBLE (-5498 2425);
FORCEADD TAP..1
R 2
(-5225 2725);
FORCEPROP 3 LASTPIN (-5175 2725) SIG_NAME UPI_CPU0_CPU1_P0P0_DP<2>
J 0
(-5165 2735);
DISPLAY 0.659574 (-5165 2735);
PAINT MONO (-5165 2735);
DISPLAY INVISIBLE (-5165 2735);
FORCEPROP 1 LASTPIN (-5175 2725) BN 2
J 2
(-5163 2733);
DISPLAY 0.617021 (-5163 2733);
PAINT GREEN (-5163 2733);
FORCEPROP 2 LAST CDS_LIB mstr_standard
J 0
(-5225 2725);
PAINT MONO (-5225 2725);
DISPLAY INVISIBLE (-5225 2725);
FORCEPROP 1 LAST BODY_TYPE PLUMBING
J 2
(-5225 2775);
DISPLAY 1.446809 (-5225 2775);
PAINT GREEN (-5225 2775);
DISPLAY INVISIBLE (-5225 2775);
FORCEPROP 1 LAST HDL_TAP TRUE
J 2
(-5550 2600);
DISPLAY 1.446809 (-5550 2600);
PAINT GREEN (-5550 2600);
DISPLAY INVISIBLE (-5550 2600);
FORCEPROP 1 LAST PATH I26
J 2
(-5223 2725);
DISPLAY 0.872340 (-5223 2725);
PAINT GREEN (-5223 2725);
DISPLAY INVISIBLE (-5223 2725);
FORCEADD TAP..1
R 2
(-5225 1725);
FORCEPROP 3 LASTPIN (-5175 1725) SIG_NAME UPI_CPU0_CPU1_P0P0_DP<3>
J 0
(-5165 1735);
DISPLAY 0.659574 (-5165 1735);
PAINT MONO (-5165 1735);
DISPLAY INVISIBLE (-5165 1735);
FORCEPROP 1 LASTPIN (-5175 1725) BN 3
J 2
(-5163 1733);
DISPLAY 0.617021 (-5163 1733);
PAINT GREEN (-5163 1733);
FORCEPROP 2 LAST CDS_LIB mstr_standard
J 0
(-5225 1725);
PAINT MONO (-5225 1725);
DISPLAY INVISIBLE (-5225 1725);
FORCEPROP 1 LAST BODY_TYPE PLUMBING
J 2
(-5225 1775);
DISPLAY 1.446809 (-5225 1775);
PAINT GREEN (-5225 1775);
DISPLAY INVISIBLE (-5225 1775);
FORCEPROP 1 LAST HDL_TAP TRUE
J 2
(-5550 1600);
DISPLAY 1.446809 (-5550 1600);
PAINT GREEN (-5550 1600);
DISPLAY INVISIBLE (-5550 1600);
FORCEPROP 1 LAST PATH I27
J 2
(-5223 1725);
DISPLAY 0.872340 (-5223 1725);
PAINT GREEN (-5223 1725);
DISPLAY INVISIBLE (-5223 1725);
FORCEADD TAP..1
R 2
(-5225 1775);
FORCEPROP 3 LASTPIN (-5175 1775) SIG_NAME UPI_CPU0_CPU1_P0P0_DP<4>
J 0
(-5165 1785);
DISPLAY 0.659574 (-5165 1785);
PAINT MONO (-5165 1785);
DISPLAY INVISIBLE (-5165 1785);
FORCEPROP 1 LASTPIN (-5175 1775) BN 4
J 2
(-5163 1783);
DISPLAY 0.617021 (-5163 1783);
PAINT GREEN (-5163 1783);
FORCEPROP 2 LAST CDS_LIB mstr_standard
J 0
(-5225 1775);
PAINT MONO (-5225 1775);
DISPLAY INVISIBLE (-5225 1775);
FORCEPROP 1 LAST BODY_TYPE PLUMBING
J 2
(-5225 1825);
DISPLAY 1.446809 (-5225 1825);
PAINT GREEN (-5225 1825);
DISPLAY INVISIBLE (-5225 1825);
FORCEPROP 1 LAST HDL_TAP TRUE
J 2
(-5550 1650);
DISPLAY 1.446809 (-5550 1650);
PAINT GREEN (-5550 1650);
DISPLAY INVISIBLE (-5550 1650);
FORCEPROP 1 LAST PATH I28
J 2
(-5223 1775);
DISPLAY 0.872340 (-5223 1775);
PAINT GREEN (-5223 1775);
DISPLAY INVISIBLE (-5223 1775);
FORCEADD TAP..1
R 2
(-5225 3125);
FORCEPROP 3 LASTPIN (-5175 3125) SIG_NAME UPI_CPU0_CPU1_P0P0_DP<10>
J 0
(-5165 3135);
DISPLAY 0.659574 (-5165 3135);
PAINT MONO (-5165 3135);
DISPLAY INVISIBLE (-5165 3135);
FORCEPROP 1 LASTPIN (-5175 3125) BN 10
J 2
(-5163 3133);
DISPLAY 0.617021 (-5163 3133);
PAINT GREEN (-5163 3133);
FORCEPROP 2 LAST CDS_LIB mstr_standard
J 0
(-5225 3125);
PAINT MONO (-5225 3125);
DISPLAY INVISIBLE (-5225 3125);
FORCEPROP 1 LAST BODY_TYPE PLUMBING
J 2
(-5225 3175);
DISPLAY 1.446809 (-5225 3175);
PAINT GREEN (-5225 3175);
DISPLAY INVISIBLE (-5225 3175);
FORCEPROP 1 LAST HDL_TAP TRUE
J 2
(-5550 3000);
DISPLAY 1.446809 (-5550 3000);
PAINT GREEN (-5550 3000);
DISPLAY INVISIBLE (-5550 3000);
FORCEPROP 1 LAST PATH I34
J 2
(-5223 3125);
DISPLAY 0.872340 (-5223 3125);
PAINT GREEN (-5223 3125);
DISPLAY INVISIBLE (-5223 3125);
FORCEADD TAP..1
R 2
(-5225 3225);
FORCEPROP 3 LASTPIN (-5175 3225) SIG_NAME UPI_CPU0_CPU1_P0P0_DP<12>
J 0
(-5165 3235);
DISPLAY 0.659574 (-5165 3235);
PAINT MONO (-5165 3235);
DISPLAY INVISIBLE (-5165 3235);
FORCEPROP 1 LASTPIN (-5175 3225) BN 12
J 2
(-5163 3233);
DISPLAY 0.617021 (-5163 3233);
PAINT GREEN (-5163 3233);
FORCEPROP 2 LAST CDS_LIB mstr_standard
J 0
(-5225 3225);
PAINT MONO (-5225 3225);
DISPLAY INVISIBLE (-5225 3225);
FORCEPROP 1 LAST BODY_TYPE PLUMBING
J 2
(-5225 3275);
DISPLAY 1.446809 (-5225 3275);
PAINT GREEN (-5225 3275);
DISPLAY INVISIBLE (-5225 3275);
FORCEPROP 1 LAST HDL_TAP TRUE
J 2
(-5550 3100);
DISPLAY 1.446809 (-5550 3100);
PAINT GREEN (-5550 3100);
DISPLAY INVISIBLE (-5550 3100);
FORCEPROP 1 LAST PATH I36
J 2
(-5223 3225);
DISPLAY 0.872340 (-5223 3225);
PAINT GREEN (-5223 3225);
DISPLAY INVISIBLE (-5223 3225);
FORCEADD TAP..1
R 2
(-5225 3425);
FORCEPROP 3 LASTPIN (-5175 3425) SIG_NAME UPI_CPU0_CPU1_P0P0_DP<16>
J 0
(-5165 3435);
DISPLAY 0.659574 (-5165 3435);
PAINT MONO (-5165 3435);
DISPLAY INVISIBLE (-5165 3435);
FORCEPROP 1 LASTPIN (-5175 3425) BN 16
J 2
(-5163 3433);
DISPLAY 0.617021 (-5163 3433);
PAINT GREEN (-5163 3433);
FORCEPROP 2 LAST CDS_LIB mstr_standard
J 0
(-5225 3425);
PAINT MONO (-5225 3425);
DISPLAY INVISIBLE (-5225 3425);
FORCEPROP 1 LAST BODY_TYPE PLUMBING
J 2
(-5225 3475);
DISPLAY 1.446809 (-5225 3475);
PAINT GREEN (-5225 3475);
DISPLAY INVISIBLE (-5225 3475);
FORCEPROP 1 LAST HDL_TAP TRUE
J 2
(-5550 3300);
DISPLAY 1.446809 (-5550 3300);
PAINT GREEN (-5550 3300);
DISPLAY INVISIBLE (-5550 3300);
FORCEPROP 1 LAST PATH I40
J 2
(-5223 3425);
DISPLAY 0.872340 (-5223 3425);
PAINT GREEN (-5223 3425);
DISPLAY INVISIBLE (-5223 3425);
FORCEADD TAP..1
R 2
(-5225 3475);
FORCEPROP 3 LASTPIN (-5175 3475) SIG_NAME UPI_CPU0_CPU1_P0P0_DP<17>
J 0
(-5165 3485);
DISPLAY 0.659574 (-5165 3485);
PAINT MONO (-5165 3485);
DISPLAY INVISIBLE (-5165 3485);
FORCEPROP 1 LASTPIN (-5175 3475) BN 17
J 2
(-5163 3483);
DISPLAY 0.617021 (-5163 3483);
PAINT GREEN (-5163 3483);
FORCEPROP 2 LAST CDS_LIB mstr_standard
J 0
(-5225 3475);
PAINT MONO (-5225 3475);
DISPLAY INVISIBLE (-5225 3475);
FORCEPROP 1 LAST BODY_TYPE PLUMBING
J 2
(-5225 3525);
DISPLAY 1.446809 (-5225 3525);
PAINT GREEN (-5225 3525);
DISPLAY INVISIBLE (-5225 3525);
FORCEPROP 1 LAST HDL_TAP TRUE
J 2
(-5550 3350);
DISPLAY 1.446809 (-5550 3350);
PAINT GREEN (-5550 3350);
DISPLAY INVISIBLE (-5550 3350);
FORCEPROP 1 LAST PATH I41
J 2
(-5223 3475);
DISPLAY 0.872340 (-5223 3475);
PAINT GREEN (-5223 3475);
DISPLAY INVISIBLE (-5223 3475);
FORCEADD TAP..1
R 2
(-5225 2475);
FORCEPROP 3 LASTPIN (-5175 2475) SIG_NAME UPI_CPU0_CPU1_P0P0_DP<18>
J 0
(-5165 2485);
DISPLAY 0.659574 (-5165 2485);
PAINT MONO (-5165 2485);
DISPLAY INVISIBLE (-5165 2485);
FORCEPROP 1 LASTPIN (-5175 2475) BN 18
J 2
(-5163 2483);
DISPLAY 0.617021 (-5163 2483);
PAINT GREEN (-5163 2483);
FORCEPROP 2 LAST CDS_LIB mstr_standard
J 0
(-5225 2475);
PAINT MONO (-5225 2475);
DISPLAY INVISIBLE (-5225 2475);
FORCEPROP 1 LAST BODY_TYPE PLUMBING
J 2
(-5225 2525);
DISPLAY 1.446809 (-5225 2525);
PAINT GREEN (-5225 2525);
DISPLAY INVISIBLE (-5225 2525);
FORCEPROP 1 LAST HDL_TAP TRUE
J 2
(-5550 2350);
DISPLAY 1.446809 (-5550 2350);
PAINT GREEN (-5550 2350);
DISPLAY INVISIBLE (-5550 2350);
FORCEPROP 1 LAST PATH I42
J 2
(-5223 2475);
DISPLAY 0.872340 (-5223 2475);
PAINT GREEN (-5223 2475);
DISPLAY INVISIBLE (-5223 2475);
FORCEADD TAP..1
R 2
(-5225 2525);
FORCEPROP 3 LASTPIN (-5175 2525) SIG_NAME UPI_CPU0_CPU1_P0P0_DP<19>
J 0
(-5165 2535);
DISPLAY 0.659574 (-5165 2535);
PAINT MONO (-5165 2535);
DISPLAY INVISIBLE (-5165 2535);
FORCEPROP 1 LASTPIN (-5175 2525) BN 19
J 2
(-5163 2533);
DISPLAY 0.617021 (-5163 2533);
PAINT GREEN (-5163 2533);
FORCEPROP 2 LAST CDS_LIB mstr_standard
J 0
(-5225 2525);
PAINT MONO (-5225 2525);
DISPLAY INVISIBLE (-5225 2525);
FORCEPROP 1 LAST BODY_TYPE PLUMBING
J 2
(-5225 2575);
DISPLAY 1.446809 (-5225 2575);
PAINT GREEN (-5225 2575);
DISPLAY INVISIBLE (-5225 2575);
FORCEPROP 1 LAST HDL_TAP TRUE
J 2
(-5550 2400);
DISPLAY 1.446809 (-5550 2400);
PAINT GREEN (-5550 2400);
DISPLAY INVISIBLE (-5550 2400);
FORCEPROP 1 LAST PATH I43
J 2
(-5223 2525);
DISPLAY 0.872340 (-5223 2525);
PAINT GREEN (-5223 2525);
DISPLAY INVISIBLE (-5223 2525);
FORCEADD TAP..1
(-2575 1675);
FORCEPROP 3 LASTPIN (-2625 1675) SIG_NAME UPI_CPU1_CPU0_P0P0_DN<2>
J 0
(-2615 1685);
DISPLAY 0.659574 (-2615 1685);
PAINT MONO (-2615 1685);
DISPLAY INVISIBLE (-2615 1685);
FORCEPROP 1 LASTPIN (-2625 1675) BN 2
J 0
(-2637 1683);
DISPLAY 0.617021 (-2637 1683);
PAINT GREEN (-2637 1683);
FORCEPROP 2 LAST CDS_LIB mstr_standard
J 0
(-2575 1675);
PAINT MONO (-2575 1675);
DISPLAY INVISIBLE (-2575 1675);
FORCEPROP 1 LAST BODY_TYPE PLUMBING
J 0
(-2575 1725);
DISPLAY 1.446809 (-2575 1725);
PAINT GREEN (-2575 1725);
DISPLAY INVISIBLE (-2575 1725);
FORCEPROP 1 LAST HDL_TAP TRUE
J 0
(-2250 1550);
DISPLAY 1.446809 (-2250 1550);
PAINT GREEN (-2250 1550);
DISPLAY INVISIBLE (-2250 1550);
FORCEPROP 1 LAST PATH I46
J 0
(-2577 1675);
DISPLAY 0.872340 (-2577 1675);
PAINT GREEN (-2577 1675);
DISPLAY INVISIBLE (-2577 1675);
FORCEADD TAP..1
(-2575 1725);
FORCEPROP 3 LASTPIN (-2625 1725) SIG_NAME UPI_CPU1_CPU0_P0P0_DN<3>
J 0
(-2615 1735);
DISPLAY 0.659574 (-2615 1735);
PAINT MONO (-2615 1735);
DISPLAY INVISIBLE (-2615 1735);
FORCEPROP 1 LASTPIN (-2625 1725) BN 3
J 0
(-2637 1733);
DISPLAY 0.617021 (-2637 1733);
PAINT GREEN (-2637 1733);
FORCEPROP 2 LAST CDS_LIB mstr_standard
J 0
(-2575 1725);
PAINT MONO (-2575 1725);
DISPLAY INVISIBLE (-2575 1725);
FORCEPROP 1 LAST BODY_TYPE PLUMBING
J 0
(-2575 1775);
DISPLAY 1.446809 (-2575 1775);
PAINT GREEN (-2575 1775);
DISPLAY INVISIBLE (-2575 1775);
FORCEPROP 1 LAST HDL_TAP TRUE
J 0
(-2250 1600);
DISPLAY 1.446809 (-2250 1600);
PAINT GREEN (-2250 1600);
DISPLAY INVISIBLE (-2250 1600);
FORCEPROP 1 LAST PATH I48
J 0
(-2577 1725);
DISPLAY 0.872340 (-2577 1725);
PAINT GREEN (-2577 1725);
DISPLAY INVISIBLE (-2577 1725);
FORCEADD TAP..1
(-2575 2875);
FORCEPROP 3 LASTPIN (-2625 2875) SIG_NAME UPI_CPU1_CPU0_P0P0_DN<5>
J 0
(-2615 2885);
DISPLAY 0.659574 (-2615 2885);
PAINT MONO (-2615 2885);
DISPLAY INVISIBLE (-2615 2885);
FORCEPROP 1 LASTPIN (-2625 2875) BN 5
J 0
(-2637 2883);
DISPLAY 0.617021 (-2637 2883);
PAINT GREEN (-2637 2883);
FORCEPROP 2 LAST CDS_LIB mstr_standard
J 0
(-2575 2875);
PAINT MONO (-2575 2875);
DISPLAY INVISIBLE (-2575 2875);
FORCEPROP 1 LAST BODY_TYPE PLUMBING
J 0
(-2575 2925);
DISPLAY 1.446809 (-2575 2925);
PAINT GREEN (-2575 2925);
DISPLAY INVISIBLE (-2575 2925);
FORCEPROP 1 LAST HDL_TAP TRUE
J 0
(-2250 2750);
DISPLAY 1.446809 (-2250 2750);
PAINT GREEN (-2250 2750);
DISPLAY INVISIBLE (-2250 2750);
FORCEPROP 1 LAST PATH I49
J 0
(-2577 2875);
DISPLAY 0.872340 (-2577 2875);
PAINT GREEN (-2577 2875);
DISPLAY INVISIBLE (-2577 2875);
FORCEADD TAP..1
R 2
(-5500 1675);
FORCEPROP 3 LASTPIN (-5450 1675) SIG_NAME UPI_CPU0_CPU1_P0P0_DN<2>
J 0
(-5440 1685);
DISPLAY 0.659574 (-5440 1685);
PAINT MONO (-5440 1685);
DISPLAY INVISIBLE (-5440 1685);
FORCEPROP 1 LASTPIN (-5450 1675) BN 2
J 2
(-5438 1683);
DISPLAY 0.617021 (-5438 1683);
PAINT GREEN (-5438 1683);
FORCEPROP 2 LAST CDS_LIB mstr_standard
J 0
(-5500 1675);
PAINT MONO (-5500 1675);
DISPLAY INVISIBLE (-5500 1675);
FORCEPROP 1 LAST BODY_TYPE PLUMBING
J 2
(-5500 1725);
DISPLAY 1.446809 (-5500 1725);
PAINT GREEN (-5500 1725);
DISPLAY INVISIBLE (-5500 1725);
FORCEPROP 1 LAST HDL_TAP TRUE
J 2
(-5825 1550);
DISPLAY 1.446809 (-5825 1550);
PAINT GREEN (-5825 1550);
DISPLAY INVISIBLE (-5825 1550);
FORCEPROP 1 LAST PATH I5
J 2
(-5498 1675);
DISPLAY 0.872340 (-5498 1675);
PAINT GREEN (-5498 1675);
DISPLAY INVISIBLE (-5498 1675);
FORCEADD TAP..1
(-2575 1925);
FORCEPROP 3 LASTPIN (-2625 1925) SIG_NAME UPI_CPU1_CPU0_P0P0_DN<7>
J 0
(-2615 1935);
DISPLAY 0.659574 (-2615 1935);
PAINT MONO (-2615 1935);
DISPLAY INVISIBLE (-2615 1935);
FORCEPROP 1 LASTPIN (-2625 1925) BN 7
J 0
(-2637 1933);
DISPLAY 0.617021 (-2637 1933);
PAINT GREEN (-2637 1933);
FORCEPROP 2 LAST CDS_LIB mstr_standard
J 0
(-2575 1925);
PAINT MONO (-2575 1925);
DISPLAY INVISIBLE (-2575 1925);
FORCEPROP 1 LAST BODY_TYPE PLUMBING
J 0
(-2575 1975);
DISPLAY 1.446809 (-2575 1975);
PAINT GREEN (-2575 1975);
DISPLAY INVISIBLE (-2575 1975);
FORCEPROP 1 LAST HDL_TAP TRUE
J 0
(-2250 1800);
DISPLAY 1.446809 (-2250 1800);
PAINT GREEN (-2250 1800);
DISPLAY INVISIBLE (-2250 1800);
FORCEPROP 1 LAST PATH I51
J 0
(-2577 1925);
DISPLAY 0.872340 (-2577 1925);
PAINT GREEN (-2577 1925);
DISPLAY INVISIBLE (-2577 1925);
FORCEADD TAP..1
(-2575 3125);
FORCEPROP 3 LASTPIN (-2625 3125) SIG_NAME UPI_CPU1_CPU0_P0P0_DN<10>
J 0
(-2615 3135);
DISPLAY 0.659574 (-2615 3135);
PAINT MONO (-2615 3135);
DISPLAY INVISIBLE (-2615 3135);
FORCEPROP 1 LASTPIN (-2625 3125) BN 10
J 0
(-2637 3133);
DISPLAY 0.617021 (-2637 3133);
PAINT GREEN (-2637 3133);
FORCEPROP 2 LAST CDS_LIB mstr_standard
J 0
(-2575 3125);
PAINT MONO (-2575 3125);
DISPLAY INVISIBLE (-2575 3125);
FORCEPROP 1 LAST BODY_TYPE PLUMBING
J 0
(-2575 3175);
DISPLAY 1.446809 (-2575 3175);
PAINT GREEN (-2575 3175);
DISPLAY INVISIBLE (-2575 3175);
FORCEPROP 1 LAST HDL_TAP TRUE
J 0
(-2250 3000);
DISPLAY 1.446809 (-2250 3000);
PAINT GREEN (-2250 3000);
DISPLAY INVISIBLE (-2250 3000);
FORCEPROP 1 LAST PATH I53
J 0
(-2577 3125);
DISPLAY 0.872340 (-2577 3125);
PAINT GREEN (-2577 3125);
DISPLAY INVISIBLE (-2577 3125);
FORCEADD TAP..1
(-2575 2025);
FORCEPROP 3 LASTPIN (-2625 2025) SIG_NAME UPI_CPU1_CPU0_P0P0_DN<9>
J 0
(-2615 2035);
DISPLAY 0.659574 (-2615 2035);
PAINT MONO (-2615 2035);
DISPLAY INVISIBLE (-2615 2035);
FORCEPROP 1 LASTPIN (-2625 2025) BN 9
J 0
(-2637 2033);
DISPLAY 0.617021 (-2637 2033);
PAINT GREEN (-2637 2033);
FORCEPROP 2 LAST CDS_LIB mstr_standard
J 0
(-2575 2025);
PAINT MONO (-2575 2025);
DISPLAY INVISIBLE (-2575 2025);
FORCEPROP 1 LAST BODY_TYPE PLUMBING
J 0
(-2575 2075);
DISPLAY 1.446809 (-2575 2075);
PAINT GREEN (-2575 2075);
DISPLAY INVISIBLE (-2575 2075);
FORCEPROP 1 LAST HDL_TAP TRUE
J 0
(-2250 1900);
DISPLAY 1.446809 (-2250 1900);
PAINT GREEN (-2250 1900);
DISPLAY INVISIBLE (-2250 1900);
FORCEPROP 1 LAST PATH I54
J 0
(-2577 2025);
DISPLAY 0.872340 (-2577 2025);
PAINT GREEN (-2577 2025);
DISPLAY INVISIBLE (-2577 2025);
FORCEADD TAP..1
(-2575 3325);
FORCEPROP 3 LASTPIN (-2625 3325) SIG_NAME UPI_CPU1_CPU0_P0P0_DN<14>
J 0
(-2615 3335);
DISPLAY 0.659574 (-2615 3335);
PAINT MONO (-2615 3335);
DISPLAY INVISIBLE (-2615 3335);
FORCEPROP 1 LASTPIN (-2625 3325) BN 14
J 0
(-2637 3333);
DISPLAY 0.617021 (-2637 3333);
PAINT GREEN (-2637 3333);
FORCEPROP 2 LAST CDS_LIB mstr_standard
J 0
(-2575 3325);
PAINT MONO (-2575 3325);
DISPLAY INVISIBLE (-2575 3325);
FORCEPROP 1 LAST BODY_TYPE PLUMBING
J 0
(-2575 3375);
DISPLAY 1.446809 (-2575 3375);
PAINT GREEN (-2575 3375);
DISPLAY INVISIBLE (-2575 3375);
FORCEPROP 1 LAST HDL_TAP TRUE
J 0
(-2250 3200);
DISPLAY 1.446809 (-2250 3200);
PAINT GREEN (-2250 3200);
DISPLAY INVISIBLE (-2250 3200);
FORCEPROP 1 LAST PATH I58
J 0
(-2577 3325);
DISPLAY 0.872340 (-2577 3325);
PAINT GREEN (-2577 3325);
DISPLAY INVISIBLE (-2577 3325);
FORCEADD TAP..1
R 2
(-5500 2825);
FORCEPROP 3 LASTPIN (-5450 2825) SIG_NAME UPI_CPU0_CPU1_P0P0_DN<4>
J 0
(-5440 2835);
DISPLAY 0.659574 (-5440 2835);
PAINT MONO (-5440 2835);
DISPLAY INVISIBLE (-5440 2835);
FORCEPROP 1 LASTPIN (-5450 2825) BN 4
J 2
(-5438 2833);
DISPLAY 0.617021 (-5438 2833);
PAINT GREEN (-5438 2833);
FORCEPROP 2 LAST CDS_LIB mstr_standard
J 0
(-5500 2825);
PAINT MONO (-5500 2825);
DISPLAY INVISIBLE (-5500 2825);
FORCEPROP 1 LAST BODY_TYPE PLUMBING
J 2
(-5500 2875);
DISPLAY 1.446809 (-5500 2875);
PAINT GREEN (-5500 2875);
DISPLAY INVISIBLE (-5500 2875);
FORCEPROP 1 LAST HDL_TAP TRUE
J 2
(-5825 2700);
DISPLAY 1.446809 (-5825 2700);
PAINT GREEN (-5825 2700);
DISPLAY INVISIBLE (-5825 2700);
FORCEPROP 1 LAST PATH I6
J 2
(-5498 2825);
DISPLAY 0.872340 (-5498 2825);
PAINT GREEN (-5498 2825);
DISPLAY INVISIBLE (-5498 2825);
FORCEADD TAP..1
(-2575 2425);
FORCEPROP 3 LASTPIN (-2625 2425) SIG_NAME UPI_CPU1_CPU0_P0P0_DN<17>
J 0
(-2615 2435);
DISPLAY 0.659574 (-2615 2435);
PAINT MONO (-2615 2435);
DISPLAY INVISIBLE (-2615 2435);
FORCEPROP 1 LASTPIN (-2625 2425) BN 17
J 0
(-2637 2433);
DISPLAY 0.617021 (-2637 2433);
PAINT GREEN (-2637 2433);
FORCEPROP 2 LAST CDS_LIB mstr_standard
J 0
(-2575 2425);
PAINT MONO (-2575 2425);
DISPLAY INVISIBLE (-2575 2425);
FORCEPROP 1 LAST BODY_TYPE PLUMBING
J 0
(-2575 2475);
DISPLAY 1.446809 (-2575 2475);
PAINT GREEN (-2575 2475);
DISPLAY INVISIBLE (-2575 2475);
FORCEPROP 1 LAST HDL_TAP TRUE
J 0
(-2250 2300);
DISPLAY 1.446809 (-2250 2300);
PAINT GREEN (-2250 2300);
DISPLAY INVISIBLE (-2250 2300);
FORCEPROP 1 LAST PATH I61
J 0
(-2577 2425);
DISPLAY 0.872340 (-2577 2425);
PAINT GREEN (-2577 2425);
DISPLAY INVISIBLE (-2577 2425);
FORCEADD TAP..1
(-2575 2475);
FORCEPROP 3 LASTPIN (-2625 2475) SIG_NAME UPI_CPU1_CPU0_P0P0_DN<18>
J 0
(-2615 2485);
DISPLAY 0.659574 (-2615 2485);
PAINT MONO (-2615 2485);
DISPLAY INVISIBLE (-2615 2485);
FORCEPROP 1 LASTPIN (-2625 2475) BN 18
J 0
(-2637 2483);
DISPLAY 0.617021 (-2637 2483);
PAINT GREEN (-2637 2483);
FORCEPROP 2 LAST CDS_LIB mstr_standard
J 0
(-2575 2475);
PAINT MONO (-2575 2475);
DISPLAY INVISIBLE (-2575 2475);
FORCEPROP 1 LAST BODY_TYPE PLUMBING
J 0
(-2575 2525);
DISPLAY 1.446809 (-2575 2525);
PAINT GREEN (-2575 2525);
DISPLAY INVISIBLE (-2575 2525);
FORCEPROP 1 LAST HDL_TAP TRUE
J 0
(-2250 2350);
DISPLAY 1.446809 (-2250 2350);
PAINT GREEN (-2250 2350);
DISPLAY INVISIBLE (-2250 2350);
FORCEPROP 1 LAST PATH I62
J 0
(-2577 2475);
DISPLAY 0.872340 (-2577 2475);
PAINT GREEN (-2577 2475);
DISPLAY INVISIBLE (-2577 2475);
FORCEADD TAP..1
(-2900 2725);
FORCEPROP 3 LASTPIN (-2950 2725) SIG_NAME UPI_CPU1_CPU0_P0P0_DP<2>
J 0
(-2940 2735);
DISPLAY 0.659574 (-2940 2735);
PAINT MONO (-2940 2735);
DISPLAY INVISIBLE (-2940 2735);
FORCEPROP 1 LASTPIN (-2950 2725) BN 2
J 0
(-2962 2733);
DISPLAY 0.617021 (-2962 2733);
PAINT GREEN (-2962 2733);
FORCEPROP 2 LAST CDS_LIB mstr_standard
J 0
(-2900 2725);
PAINT MONO (-2900 2725);
DISPLAY INVISIBLE (-2900 2725);
FORCEPROP 1 LAST BODY_TYPE PLUMBING
J 0
(-2900 2775);
DISPLAY 1.446809 (-2900 2775);
PAINT GREEN (-2900 2775);
DISPLAY INVISIBLE (-2900 2775);
FORCEPROP 1 LAST HDL_TAP TRUE
J 0
(-2575 2600);
DISPLAY 1.446809 (-2575 2600);
PAINT GREEN (-2575 2600);
DISPLAY INVISIBLE (-2575 2600);
FORCEPROP 1 LAST PATH I66
J 0
(-2902 2725);
DISPLAY 0.872340 (-2902 2725);
PAINT GREEN (-2902 2725);
DISPLAY INVISIBLE (-2902 2725);
FORCEADD TAP..1
(-2900 2775);
FORCEPROP 3 LASTPIN (-2950 2775) SIG_NAME UPI_CPU1_CPU0_P0P0_DP<3>
J 0
(-2940 2785);
DISPLAY 0.659574 (-2940 2785);
PAINT MONO (-2940 2785);
DISPLAY INVISIBLE (-2940 2785);
FORCEPROP 1 LASTPIN (-2950 2775) BN 3
J 0
(-2962 2783);
DISPLAY 0.617021 (-2962 2783);
PAINT GREEN (-2962 2783);
FORCEPROP 2 LAST CDS_LIB mstr_standard
J 0
(-2900 2775);
PAINT MONO (-2900 2775);
DISPLAY INVISIBLE (-2900 2775);
FORCEPROP 1 LAST BODY_TYPE PLUMBING
J 0
(-2900 2825);
DISPLAY 1.446809 (-2900 2825);
PAINT GREEN (-2900 2825);
DISPLAY INVISIBLE (-2900 2825);
FORCEPROP 1 LAST HDL_TAP TRUE
J 0
(-2575 2650);
DISPLAY 1.446809 (-2575 2650);
PAINT GREEN (-2575 2650);
DISPLAY INVISIBLE (-2575 2650);
FORCEPROP 1 LAST PATH I67
J 0
(-2902 2775);
DISPLAY 0.872340 (-2902 2775);
PAINT GREEN (-2902 2775);
DISPLAY INVISIBLE (-2902 2775);
FORCEADD TAP..1
(-2900 1825);
FORCEPROP 3 LASTPIN (-2950 1825) SIG_NAME UPI_CPU1_CPU0_P0P0_DP<5>
J 0
(-2940 1835);
DISPLAY 0.659574 (-2940 1835);
PAINT MONO (-2940 1835);
DISPLAY INVISIBLE (-2940 1835);
FORCEPROP 1 LASTPIN (-2950 1825) BN 5
J 0
(-2962 1833);
DISPLAY 0.617021 (-2962 1833);
PAINT GREEN (-2962 1833);
FORCEPROP 2 LAST CDS_LIB mstr_standard
J 0
(-2900 1825);
PAINT MONO (-2900 1825);
DISPLAY INVISIBLE (-2900 1825);
FORCEPROP 1 LAST BODY_TYPE PLUMBING
J 0
(-2900 1875);
DISPLAY 1.446809 (-2900 1875);
PAINT GREEN (-2900 1875);
DISPLAY INVISIBLE (-2900 1875);
FORCEPROP 1 LAST HDL_TAP TRUE
J 0
(-2575 1700);
DISPLAY 1.446809 (-2575 1700);
PAINT GREEN (-2575 1700);
DISPLAY INVISIBLE (-2575 1700);
FORCEPROP 1 LAST PATH I69
J 0
(-2902 1825);
DISPLAY 0.872340 (-2902 1825);
PAINT GREEN (-2902 1825);
DISPLAY INVISIBLE (-2902 1825);
FORCEADD TAP..1
R 2
(-5500 2775);
FORCEPROP 3 LASTPIN (-5450 2775) SIG_NAME UPI_CPU0_CPU1_P0P0_DN<3>
J 0
(-5440 2785);
DISPLAY 0.659574 (-5440 2785);
PAINT MONO (-5440 2785);
DISPLAY INVISIBLE (-5440 2785);
FORCEPROP 1 LASTPIN (-5450 2775) BN 3
J 2
(-5438 2783);
DISPLAY 0.617021 (-5438 2783);
PAINT GREEN (-5438 2783);
FORCEPROP 2 LAST CDS_LIB mstr_standard
J 0
(-5500 2775);
PAINT MONO (-5500 2775);
DISPLAY INVISIBLE (-5500 2775);
FORCEPROP 1 LAST BODY_TYPE PLUMBING
J 2
(-5500 2825);
DISPLAY 1.446809 (-5500 2825);
PAINT GREEN (-5500 2825);
DISPLAY INVISIBLE (-5500 2825);
FORCEPROP 1 LAST HDL_TAP TRUE
J 2
(-5825 2650);
DISPLAY 1.446809 (-5825 2650);
PAINT GREEN (-5825 2650);
DISPLAY INVISIBLE (-5825 2650);
FORCEPROP 1 LAST PATH I7
J 2
(-5498 2775);
DISPLAY 0.872340 (-5498 2775);
PAINT GREEN (-5498 2775);
DISPLAY INVISIBLE (-5498 2775);
FORCEADD TAP..1
(-2900 2975);
FORCEPROP 3 LASTPIN (-2950 2975) SIG_NAME UPI_CPU1_CPU0_P0P0_DP<7>
J 0
(-2940 2985);
DISPLAY 0.659574 (-2940 2985);
PAINT MONO (-2940 2985);
DISPLAY INVISIBLE (-2940 2985);
FORCEPROP 1 LASTPIN (-2950 2975) BN 7
J 0
(-2962 2983);
DISPLAY 0.617021 (-2962 2983);
PAINT GREEN (-2962 2983);
FORCEPROP 2 LAST CDS_LIB mstr_standard
J 0
(-2900 2975);
PAINT MONO (-2900 2975);
DISPLAY INVISIBLE (-2900 2975);
FORCEPROP 1 LAST BODY_TYPE PLUMBING
J 0
(-2900 3025);
DISPLAY 1.446809 (-2900 3025);
PAINT GREEN (-2900 3025);
DISPLAY INVISIBLE (-2900 3025);
FORCEPROP 1 LAST HDL_TAP TRUE
J 0
(-2575 2850);
DISPLAY 1.446809 (-2575 2850);
PAINT GREEN (-2575 2850);
DISPLAY INVISIBLE (-2575 2850);
FORCEPROP 1 LAST PATH I72
J 0
(-2902 2975);
DISPLAY 0.872340 (-2902 2975);
PAINT GREEN (-2902 2975);
DISPLAY INVISIBLE (-2902 2975);
FORCEADD TAP..1
(-2900 3075);
FORCEPROP 3 LASTPIN (-2950 3075) SIG_NAME UPI_CPU1_CPU0_P0P0_DP<9>
J 0
(-2940 3085);
DISPLAY 0.659574 (-2940 3085);
PAINT MONO (-2940 3085);
DISPLAY INVISIBLE (-2940 3085);
FORCEPROP 1 LASTPIN (-2950 3075) BN 9
J 0
(-2962 3083);
DISPLAY 0.617021 (-2962 3083);
PAINT GREEN (-2962 3083);
FORCEPROP 2 LAST CDS_LIB mstr_standard
J 0
(-2900 3075);
PAINT MONO (-2900 3075);
DISPLAY INVISIBLE (-2900 3075);
FORCEPROP 1 LAST BODY_TYPE PLUMBING
J 0
(-2900 3125);
DISPLAY 1.446809 (-2900 3125);
PAINT GREEN (-2900 3125);
DISPLAY INVISIBLE (-2900 3125);
FORCEPROP 1 LAST HDL_TAP TRUE
J 0
(-2575 2950);
DISPLAY 1.446809 (-2575 2950);
PAINT GREEN (-2575 2950);
DISPLAY INVISIBLE (-2575 2950);
FORCEPROP 1 LAST PATH I73
J 0
(-2902 3075);
DISPLAY 0.872340 (-2902 3075);
PAINT GREEN (-2902 3075);
DISPLAY INVISIBLE (-2902 3075);
FORCEADD TAP..1
(-2900 2075);
FORCEPROP 3 LASTPIN (-2950 2075) SIG_NAME UPI_CPU1_CPU0_P0P0_DP<10>
J 0
(-2940 2085);
DISPLAY 0.659574 (-2940 2085);
PAINT MONO (-2940 2085);
DISPLAY INVISIBLE (-2940 2085);
FORCEPROP 1 LASTPIN (-2950 2075) BN 10
J 0
(-2962 2083);
DISPLAY 0.617021 (-2962 2083);
PAINT GREEN (-2962 2083);
FORCEPROP 2 LAST CDS_LIB mstr_standard
J 0
(-2900 2075);
PAINT MONO (-2900 2075);
DISPLAY INVISIBLE (-2900 2075);
FORCEPROP 1 LAST BODY_TYPE PLUMBING
J 0
(-2900 2125);
DISPLAY 1.446809 (-2900 2125);
PAINT GREEN (-2900 2125);
DISPLAY INVISIBLE (-2900 2125);
FORCEPROP 1 LAST HDL_TAP TRUE
J 0
(-2575 1950);
DISPLAY 1.446809 (-2575 1950);
PAINT GREEN (-2575 1950);
DISPLAY INVISIBLE (-2575 1950);
FORCEPROP 1 LAST PATH I74
J 0
(-2902 2075);
DISPLAY 0.872340 (-2902 2075);
PAINT GREEN (-2902 2075);
DISPLAY INVISIBLE (-2902 2075);
FORCEADD TAP..1
(-2900 2275);
FORCEPROP 3 LASTPIN (-2950 2275) SIG_NAME UPI_CPU1_CPU0_P0P0_DP<14>
J 0
(-2940 2285);
DISPLAY 0.659574 (-2940 2285);
PAINT MONO (-2940 2285);
DISPLAY INVISIBLE (-2940 2285);
FORCEPROP 1 LASTPIN (-2950 2275) BN 14
J 0
(-2962 2283);
DISPLAY 0.617021 (-2962 2283);
PAINT GREEN (-2962 2283);
FORCEPROP 2 LAST CDS_LIB mstr_standard
J 0
(-2900 2275);
PAINT MONO (-2900 2275);
DISPLAY INVISIBLE (-2900 2275);
FORCEPROP 1 LAST BODY_TYPE PLUMBING
J 0
(-2900 2325);
DISPLAY 1.446809 (-2900 2325);
PAINT GREEN (-2900 2325);
DISPLAY INVISIBLE (-2900 2325);
FORCEPROP 1 LAST HDL_TAP TRUE
J 0
(-2575 2150);
DISPLAY 1.446809 (-2575 2150);
PAINT GREEN (-2575 2150);
DISPLAY INVISIBLE (-2575 2150);
FORCEPROP 1 LAST PATH I78
J 0
(-2902 2275);
DISPLAY 0.872340 (-2902 2275);
PAINT GREEN (-2902 2275);
DISPLAY INVISIBLE (-2902 2275);
FORCEADD TAP..1
(-2900 3475);
FORCEPROP 3 LASTPIN (-2950 3475) SIG_NAME UPI_CPU1_CPU0_P0P0_DP<17>
J 0
(-2940 3485);
DISPLAY 0.659574 (-2940 3485);
PAINT MONO (-2940 3485);
DISPLAY INVISIBLE (-2940 3485);
FORCEPROP 1 LASTPIN (-2950 3475) BN 17
J 0
(-2962 3483);
DISPLAY 0.617021 (-2962 3483);
PAINT GREEN (-2962 3483);
FORCEPROP 2 LAST CDS_LIB mstr_standard
J 0
(-2900 3475);
PAINT MONO (-2900 3475);
DISPLAY INVISIBLE (-2900 3475);
FORCEPROP 1 LAST BODY_TYPE PLUMBING
J 0
(-2900 3525);
DISPLAY 1.446809 (-2900 3525);
PAINT GREEN (-2900 3525);
DISPLAY INVISIBLE (-2900 3525);
FORCEPROP 1 LAST HDL_TAP TRUE
J 0
(-2575 3350);
DISPLAY 1.446809 (-2575 3350);
PAINT GREEN (-2575 3350);
DISPLAY INVISIBLE (-2575 3350);
FORCEPROP 1 LAST PATH I81
J 0
(-2902 3475);
DISPLAY 0.872340 (-2902 3475);
PAINT GREEN (-2902 3475);
DISPLAY INVISIBLE (-2902 3475);
FORCEADD TAP..1
(-2900 3525);
FORCEPROP 3 LASTPIN (-2950 3525) SIG_NAME UPI_CPU1_CPU0_P0P0_DP<18>
J 0
(-2940 3535);
DISPLAY 0.659574 (-2940 3535);
PAINT MONO (-2940 3535);
DISPLAY INVISIBLE (-2940 3535);
FORCEPROP 1 LASTPIN (-2950 3525) BN 18
J 0
(-2962 3533);
DISPLAY 0.617021 (-2962 3533);
PAINT GREEN (-2962 3533);
FORCEPROP 2 LAST CDS_LIB mstr_standard
J 0
(-2900 3525);
PAINT MONO (-2900 3525);
DISPLAY INVISIBLE (-2900 3525);
FORCEPROP 1 LAST BODY_TYPE PLUMBING
J 0
(-2900 3575);
DISPLAY 1.446809 (-2900 3575);
PAINT GREEN (-2900 3575);
DISPLAY INVISIBLE (-2900 3575);
FORCEPROP 1 LAST HDL_TAP TRUE
J 0
(-2575 3400);
DISPLAY 1.446809 (-2575 3400);
PAINT GREEN (-2575 3400);
DISPLAY INVISIBLE (-2575 3400);
FORCEPROP 1 LAST PATH I83
J 0
(-2902 3525);
DISPLAY 0.872340 (-2902 3525);
PAINT GREEN (-2902 3525);
DISPLAY INVISIBLE (-2902 3525);
FORCEADD OFFPAGE..2
(-1550 3650);
FORCEPROP 2 LAST $XR0 33 
J 0
(-1361 3650);
DISPLAY 0.638298 (-1361 3650);
PAINT MONO (-1361 3650);
FORCEPROP 2 LAST CDS_LIB mstr_standard
J 0
(-1550 3650);
PAINT MONO (-1550 3650);
DISPLAY INVISIBLE (-1550 3650);
FORCEPROP 1 LAST OFFPAGE TRUE
J 0
(-1225 3525);
DISPLAY 1.170213 (-1225 3525);
PAINT GREEN (-1225 3525);
DISPLAY INVISIBLE (-1225 3525);
FORCEPROP 1 LAST COMMENT_BODY TRUE
J 0
(-1595 3555);
DISPLAY 1.170213 (-1595 3555);
PAINT GREEN (-1595 3555);
DISPLAY INVISIBLE (-1595 3555);
FORCEPROP 2 LAST PATH I84
J 0
(-1375 3725);
DISPLAY 1.021277 (-1375 3725);
PAINT ORANGE (-1375 3725);
DISPLAY INVISIBLE (-1375 3725);
FORCEADD OFFPAGE..2
(-1550 3725);
FORCEPROP 2 LAST $XR0 33 
J 0
(-1361 3725);
DISPLAY 0.638298 (-1361 3725);
PAINT MONO (-1361 3725);
FORCEPROP 2 LAST CDS_LIB mstr_standard
J 0
(-1550 3725);
PAINT MONO (-1550 3725);
DISPLAY INVISIBLE (-1550 3725);
FORCEPROP 1 LAST OFFPAGE TRUE
J 0
(-1225 3600);
DISPLAY 1.170213 (-1225 3600);
PAINT GREEN (-1225 3600);
DISPLAY INVISIBLE (-1225 3600);
FORCEPROP 1 LAST COMMENT_BODY TRUE
J 0
(-1595 3630);
DISPLAY 1.170213 (-1595 3630);
PAINT GREEN (-1595 3630);
DISPLAY INVISIBLE (-1595 3630);
FORCEPROP 2 LAST PATH I85
J 0
(-1375 3800);
DISPLAY 1.021277 (-1375 3800);
PAINT ORANGE (-1375 3800);
DISPLAY INVISIBLE (-1375 3800);
FORCEADD TAP..1
R 2
(-5500 3525);
FORCEPROP 3 LASTPIN (-5450 3525) SIG_NAME UPI_CPU0_CPU1_P0P0_DN<18>
J 0
(-5440 3535);
DISPLAY 0.659574 (-5440 3535);
PAINT MONO (-5440 3535);
DISPLAY INVISIBLE (-5440 3535);
FORCEPROP 1 LASTPIN (-5450 3525) BN 18
J 2
(-5438 3533);
DISPLAY 0.617021 (-5438 3533);
PAINT GREEN (-5438 3533);
FORCEPROP 2 LAST CDS_LIB mstr_standard
J 0
(-5500 3525);
PAINT MONO (-5500 3525);
DISPLAY INVISIBLE (-5500 3525);
FORCEPROP 1 LAST BODY_TYPE PLUMBING
J 2
(-5500 3575);
DISPLAY 1.446809 (-5500 3575);
PAINT GREEN (-5500 3575);
DISPLAY INVISIBLE (-5500 3575);
FORCEPROP 1 LAST HDL_TAP TRUE
J 2
(-5825 3400);
DISPLAY 1.446809 (-5825 3400);
PAINT GREEN (-5825 3400);
DISPLAY INVISIBLE (-5825 3400);
FORCEPROP 1 LAST PATH I86
J 2
(-5498 3525);
DISPLAY 0.872340 (-5498 3525);
PAINT GREEN (-5498 3525);
DISPLAY INVISIBLE (-5498 3525);
FORCEADD TAP..1
R 2
(-5500 3575);
FORCEPROP 3 LASTPIN (-5450 3575) SIG_NAME UPI_CPU0_CPU1_P0P0_DN<19>
J 0
(-5440 3585);
DISPLAY 0.659574 (-5440 3585);
PAINT MONO (-5440 3585);
DISPLAY INVISIBLE (-5440 3585);
FORCEPROP 1 LASTPIN (-5450 3575) BN 19
J 2
(-5438 3583);
DISPLAY 0.617021 (-5438 3583);
PAINT GREEN (-5438 3583);
FORCEPROP 2 LAST CDS_LIB mstr_standard
J 0
(-5500 3575);
PAINT MONO (-5500 3575);
DISPLAY INVISIBLE (-5500 3575);
FORCEPROP 1 LAST BODY_TYPE PLUMBING
J 2
(-5500 3625);
DISPLAY 1.446809 (-5500 3625);
PAINT GREEN (-5500 3625);
DISPLAY INVISIBLE (-5500 3625);
FORCEPROP 1 LAST HDL_TAP TRUE
J 2
(-5825 3450);
DISPLAY 1.446809 (-5825 3450);
PAINT GREEN (-5825 3450);
DISPLAY INVISIBLE (-5825 3450);
FORCEPROP 1 LAST PATH I87
J 2
(-5498 3575);
DISPLAY 0.872340 (-5498 3575);
PAINT GREEN (-5498 3575);
DISPLAY INVISIBLE (-5498 3575);
FORCEADD TAP..1
R 2
(-5500 2625);
FORCEPROP 3 LASTPIN (-5450 2625) SIG_NAME UPI_CPU0_CPU1_P0P0_DN<0>
J 0
(-5440 2635);
DISPLAY 0.659574 (-5440 2635);
PAINT MONO (-5440 2635);
DISPLAY INVISIBLE (-5440 2635);
FORCEPROP 1 LASTPIN (-5450 2625) BN 0
J 2
(-5438 2633);
DISPLAY 0.617021 (-5438 2633);
PAINT GREEN (-5438 2633);
FORCEPROP 2 LAST CDS_LIB mstr_standard
J 0
(-5500 2625);
PAINT MONO (-5500 2625);
DISPLAY INVISIBLE (-5500 2625);
FORCEPROP 1 LAST BODY_TYPE PLUMBING
J 2
(-5500 2675);
DISPLAY 1.446809 (-5500 2675);
PAINT GREEN (-5500 2675);
DISPLAY INVISIBLE (-5500 2675);
FORCEPROP 1 LAST HDL_TAP TRUE
J 2
(-5825 2500);
DISPLAY 1.446809 (-5825 2500);
PAINT GREEN (-5825 2500);
DISPLAY INVISIBLE (-5825 2500);
FORCEPROP 1 LAST PATH I88
J 2
(-5498 2625);
DISPLAY 0.872340 (-5498 2625);
PAINT GREEN (-5498 2625);
DISPLAY INVISIBLE (-5498 2625);
FORCEADD TAP..1
R 2
(-5500 2875);
FORCEPROP 3 LASTPIN (-5450 2875) SIG_NAME UPI_CPU0_CPU1_P0P0_DN<5>
J 0
(-5440 2885);
DISPLAY 0.659574 (-5440 2885);
PAINT MONO (-5440 2885);
DISPLAY INVISIBLE (-5440 2885);
FORCEPROP 1 LASTPIN (-5450 2875) BN 5
J 2
(-5438 2883);
DISPLAY 0.617021 (-5438 2883);
PAINT GREEN (-5438 2883);
FORCEPROP 2 LAST CDS_LIB mstr_standard
J 0
(-5500 2875);
PAINT MONO (-5500 2875);
DISPLAY INVISIBLE (-5500 2875);
FORCEPROP 1 LAST BODY_TYPE PLUMBING
J 2
(-5500 2925);
DISPLAY 1.446809 (-5500 2925);
PAINT GREEN (-5500 2925);
DISPLAY INVISIBLE (-5500 2925);
FORCEPROP 1 LAST HDL_TAP TRUE
J 2
(-5825 2750);
DISPLAY 1.446809 (-5825 2750);
PAINT GREEN (-5825 2750);
DISPLAY INVISIBLE (-5825 2750);
FORCEPROP 1 LAST PATH I89
J 2
(-5498 2875);
DISPLAY 0.872340 (-5498 2875);
PAINT GREEN (-5498 2875);
DISPLAY INVISIBLE (-5498 2875);
FORCEADD TAP..1
R 2
(-5500 2925);
FORCEPROP 3 LASTPIN (-5450 2925) SIG_NAME UPI_CPU0_CPU1_P0P0_DN<6>
J 0
(-5440 2935);
DISPLAY 0.659574 (-5440 2935);
PAINT MONO (-5440 2935);
DISPLAY INVISIBLE (-5440 2935);
FORCEPROP 1 LASTPIN (-5450 2925) BN 6
J 2
(-5438 2933);
DISPLAY 0.617021 (-5438 2933);
PAINT GREEN (-5438 2933);
FORCEPROP 2 LAST CDS_LIB mstr_standard
J 0
(-5500 2925);
PAINT MONO (-5500 2925);
DISPLAY INVISIBLE (-5500 2925);
FORCEPROP 1 LAST BODY_TYPE PLUMBING
J 2
(-5500 2975);
DISPLAY 1.446809 (-5500 2975);
PAINT GREEN (-5500 2975);
DISPLAY INVISIBLE (-5500 2975);
FORCEPROP 1 LAST HDL_TAP TRUE
J 2
(-5825 2800);
DISPLAY 1.446809 (-5825 2800);
PAINT GREEN (-5825 2800);
DISPLAY INVISIBLE (-5825 2800);
FORCEPROP 1 LAST PATH I90
J 2
(-5498 2925);
DISPLAY 0.872340 (-5498 2925);
PAINT GREEN (-5498 2925);
DISPLAY INVISIBLE (-5498 2925);
FORCEADD TAP..1
R 2
(-5500 2975);
FORCEPROP 3 LASTPIN (-5450 2975) SIG_NAME UPI_CPU0_CPU1_P0P0_DN<7>
J 0
(-5440 2985);
DISPLAY 0.659574 (-5440 2985);
PAINT MONO (-5440 2985);
DISPLAY INVISIBLE (-5440 2985);
FORCEPROP 1 LASTPIN (-5450 2975) BN 7
J 2
(-5438 2983);
DISPLAY 0.617021 (-5438 2983);
PAINT GREEN (-5438 2983);
FORCEPROP 2 LAST CDS_LIB mstr_standard
J 0
(-5500 2975);
PAINT MONO (-5500 2975);
DISPLAY INVISIBLE (-5500 2975);
FORCEPROP 1 LAST BODY_TYPE PLUMBING
J 2
(-5500 3025);
DISPLAY 1.446809 (-5500 3025);
PAINT GREEN (-5500 3025);
DISPLAY INVISIBLE (-5500 3025);
FORCEPROP 1 LAST HDL_TAP TRUE
J 2
(-5825 2850);
DISPLAY 1.446809 (-5825 2850);
PAINT GREEN (-5825 2850);
DISPLAY INVISIBLE (-5825 2850);
FORCEPROP 1 LAST PATH I91
J 2
(-5498 2975);
DISPLAY 0.872340 (-5498 2975);
PAINT GREEN (-5498 2975);
DISPLAY INVISIBLE (-5498 2975);
FORCEADD TAP..1
R 2
(-5500 3025);
FORCEPROP 3 LASTPIN (-5450 3025) SIG_NAME UPI_CPU0_CPU1_P0P0_DN<8>
J 0
(-5440 3035);
DISPLAY 0.659574 (-5440 3035);
PAINT MONO (-5440 3035);
DISPLAY INVISIBLE (-5440 3035);
FORCEPROP 1 LASTPIN (-5450 3025) BN 8
J 2
(-5438 3033);
DISPLAY 0.617021 (-5438 3033);
PAINT GREEN (-5438 3033);
FORCEPROP 2 LAST CDS_LIB mstr_standard
J 0
(-5500 3025);
PAINT MONO (-5500 3025);
DISPLAY INVISIBLE (-5500 3025);
FORCEPROP 1 LAST BODY_TYPE PLUMBING
J 2
(-5500 3075);
DISPLAY 1.446809 (-5500 3075);
PAINT GREEN (-5500 3075);
DISPLAY INVISIBLE (-5500 3075);
FORCEPROP 1 LAST HDL_TAP TRUE
J 2
(-5825 2900);
DISPLAY 1.446809 (-5825 2900);
PAINT GREEN (-5825 2900);
DISPLAY INVISIBLE (-5825 2900);
FORCEPROP 1 LAST PATH I92
J 2
(-5498 3025);
DISPLAY 0.872340 (-5498 3025);
PAINT GREEN (-5498 3025);
DISPLAY INVISIBLE (-5498 3025);
FORCEADD TAP..1
R 2
(-5500 3075);
FORCEPROP 3 LASTPIN (-5450 3075) SIG_NAME UPI_CPU0_CPU1_P0P0_DN<9>
J 0
(-5440 3085);
DISPLAY 0.659574 (-5440 3085);
PAINT MONO (-5440 3085);
DISPLAY INVISIBLE (-5440 3085);
FORCEPROP 1 LASTPIN (-5450 3075) BN 9
J 2
(-5438 3083);
DISPLAY 0.617021 (-5438 3083);
PAINT GREEN (-5438 3083);
FORCEPROP 2 LAST CDS_LIB mstr_standard
J 0
(-5500 3075);
PAINT MONO (-5500 3075);
DISPLAY INVISIBLE (-5500 3075);
FORCEPROP 1 LAST BODY_TYPE PLUMBING
J 2
(-5500 3125);
DISPLAY 1.446809 (-5500 3125);
PAINT GREEN (-5500 3125);
DISPLAY INVISIBLE (-5500 3125);
FORCEPROP 1 LAST HDL_TAP TRUE
J 2
(-5825 2950);
DISPLAY 1.446809 (-5825 2950);
PAINT GREEN (-5825 2950);
DISPLAY INVISIBLE (-5825 2950);
FORCEPROP 1 LAST PATH I93
J 2
(-5498 3075);
DISPLAY 0.872340 (-5498 3075);
PAINT GREEN (-5498 3075);
DISPLAY INVISIBLE (-5498 3075);
FORCEADD TAP..1
R 2
(-5500 2225);
FORCEPROP 3 LASTPIN (-5450 2225) SIG_NAME UPI_CPU0_CPU1_P0P0_DN<13>
J 0
(-5440 2235);
DISPLAY 0.659574 (-5440 2235);
PAINT MONO (-5440 2235);
DISPLAY INVISIBLE (-5440 2235);
FORCEPROP 1 LASTPIN (-5450 2225) BN 13
J 2
(-5438 2233);
DISPLAY 0.617021 (-5438 2233);
PAINT GREEN (-5438 2233);
FORCEPROP 2 LAST CDS_LIB mstr_standard
J 0
(-5500 2225);
PAINT ORANGE (-5500 2225);
DISPLAY INVISIBLE (-5500 2225);
FORCEPROP 1 LAST BODY_TYPE PLUMBING
J 2
(-5500 2275);
DISPLAY 1.446809 (-5500 2275);
PAINT GREEN (-5500 2275);
DISPLAY INVISIBLE (-5500 2275);
FORCEPROP 1 LAST HDL_TAP TRUE
J 2
(-5825 2100);
DISPLAY 1.446809 (-5825 2100);
PAINT GREEN (-5825 2100);
DISPLAY INVISIBLE (-5825 2100);
FORCEPROP 1 LAST PATH I94
J 2
(-5498 2225);
DISPLAY 0.872340 (-5498 2225);
PAINT GREEN (-5498 2225);
DISPLAY INVISIBLE (-5498 2225);
FORCEADD TAP..1
R 2
(-5500 3325);
FORCEPROP 3 LASTPIN (-5450 3325) SIG_NAME UPI_CPU0_CPU1_P0P0_DN<14>
J 0
(-5440 3335);
DISPLAY 0.659574 (-5440 3335);
PAINT MONO (-5440 3335);
DISPLAY INVISIBLE (-5440 3335);
FORCEPROP 1 LASTPIN (-5450 3325) BN 14
J 2
(-5438 3333);
DISPLAY 0.617021 (-5438 3333);
PAINT GREEN (-5438 3333);
FORCEPROP 2 LAST CDS_LIB mstr_standard
J 0
(-5500 3325);
PAINT MONO (-5500 3325);
DISPLAY INVISIBLE (-5500 3325);
FORCEPROP 1 LAST BODY_TYPE PLUMBING
J 2
(-5500 3375);
DISPLAY 1.446809 (-5500 3375);
PAINT GREEN (-5500 3375);
DISPLAY INVISIBLE (-5500 3375);
FORCEPROP 1 LAST HDL_TAP TRUE
J 2
(-5825 3200);
DISPLAY 1.446809 (-5825 3200);
PAINT GREEN (-5825 3200);
DISPLAY INVISIBLE (-5825 3200);
FORCEPROP 1 LAST PATH I95
J 2
(-5498 3325);
DISPLAY 0.872340 (-5498 3325);
PAINT GREEN (-5498 3325);
DISPLAY INVISIBLE (-5498 3325);
FORCEADD TAP..1
R 2
(-5500 2325);
FORCEPROP 3 LASTPIN (-5450 2325) SIG_NAME UPI_CPU0_CPU1_P0P0_DN<15>
J 0
(-5440 2335);
DISPLAY 0.659574 (-5440 2335);
PAINT MONO (-5440 2335);
DISPLAY INVISIBLE (-5440 2335);
FORCEPROP 1 LASTPIN (-5450 2325) BN 15
J 2
(-5438 2333);
DISPLAY 0.617021 (-5438 2333);
PAINT GREEN (-5438 2333);
FORCEPROP 2 LAST CDS_LIB mstr_standard
J 0
(-5500 2325);
PAINT MONO (-5500 2325);
DISPLAY INVISIBLE (-5500 2325);
FORCEPROP 1 LAST BODY_TYPE PLUMBING
J 2
(-5500 2375);
DISPLAY 1.446809 (-5500 2375);
PAINT GREEN (-5500 2375);
DISPLAY INVISIBLE (-5500 2375);
FORCEPROP 1 LAST HDL_TAP TRUE
J 2
(-5825 2200);
DISPLAY 1.446809 (-5825 2200);
PAINT GREEN (-5825 2200);
DISPLAY INVISIBLE (-5825 2200);
FORCEPROP 1 LAST PATH I96
J 2
(-5498 2325);
DISPLAY 0.872340 (-5498 2325);
PAINT GREEN (-5498 2325);
DISPLAY INVISIBLE (-5498 2325);
FORCEADD TAP..1
R 2
(-5500 3175);
FORCEPROP 3 LASTPIN (-5450 3175) SIG_NAME UPI_CPU0_CPU1_P0P0_DN<11>
J 0
(-5440 3185);
DISPLAY 0.659574 (-5440 3185);
PAINT MONO (-5440 3185);
DISPLAY INVISIBLE (-5440 3185);
FORCEPROP 1 LASTPIN (-5450 3175) BN 11
J 2
(-5438 3183);
DISPLAY 0.617021 (-5438 3183);
PAINT GREEN (-5438 3183);
FORCEPROP 2 LAST CDS_LIB mstr_standard
J 0
(-5500 3175);
PAINT MONO (-5500 3175);
DISPLAY INVISIBLE (-5500 3175);
FORCEPROP 1 LAST BODY_TYPE PLUMBING
J 2
(-5500 3225);
DISPLAY 1.446809 (-5500 3225);
PAINT GREEN (-5500 3225);
DISPLAY INVISIBLE (-5500 3225);
FORCEPROP 1 LAST HDL_TAP TRUE
J 2
(-5825 3050);
DISPLAY 1.446809 (-5825 3050);
PAINT GREEN (-5825 3050);
DISPLAY INVISIBLE (-5825 3050);
FORCEPROP 1 LAST PATH I97
J 2
(-5498 3175);
DISPLAY 0.872340 (-5498 3175);
PAINT GREEN (-5498 3175);
DISPLAY INVISIBLE (-5498 3175);
FORCEADD TAP..1
R 2
(-5225 3375);
FORCEPROP 3 LASTPIN (-5175 3375) SIG_NAME UPI_CPU0_CPU1_P0P0_DP<15>
J 0
(-5165 3385);
DISPLAY 0.659574 (-5165 3385);
PAINT MONO (-5165 3385);
DISPLAY INVISIBLE (-5165 3385);
FORCEPROP 1 LASTPIN (-5175 3375) BN 15
J 2
(-5163 3383);
DISPLAY 0.617021 (-5163 3383);
PAINT GREEN (-5163 3383);
FORCEPROP 2 LAST CDS_LIB mstr_standard
J 0
(-5225 3375);
PAINT MONO (-5225 3375);
DISPLAY INVISIBLE (-5225 3375);
FORCEPROP 1 LAST BODY_TYPE PLUMBING
J 2
(-5225 3425);
DISPLAY 1.446809 (-5225 3425);
PAINT GREEN (-5225 3425);
DISPLAY INVISIBLE (-5225 3425);
FORCEPROP 1 LAST HDL_TAP TRUE
J 2
(-5550 3250);
DISPLAY 1.446809 (-5550 3250);
PAINT GREEN (-5550 3250);
DISPLAY INVISIBLE (-5550 3250);
FORCEPROP 1 LAST PATH I98
J 2
(-5223 3375);
DISPLAY 0.872340 (-5223 3375);
PAINT GREEN (-5223 3375);
DISPLAY INVISIBLE (-5223 3375);
FORCEADD TAP..1
R 2
(-5225 2275);
FORCEPROP 3 LASTPIN (-5175 2275) SIG_NAME UPI_CPU0_CPU1_P0P0_DP<14>
J 0
(-5165 2285);
DISPLAY 0.659574 (-5165 2285);
PAINT MONO (-5165 2285);
DISPLAY INVISIBLE (-5165 2285);
FORCEPROP 1 LASTPIN (-5175 2275) BN 14
J 2
(-5163 2283);
DISPLAY 0.617021 (-5163 2283);
PAINT GREEN (-5163 2283);
FORCEPROP 2 LAST CDS_LIB mstr_standard
J 0
(-5225 2275);
PAINT MONO (-5225 2275);
DISPLAY INVISIBLE (-5225 2275);
FORCEPROP 1 LAST BODY_TYPE PLUMBING
J 2
(-5225 2325);
DISPLAY 1.446809 (-5225 2325);
PAINT GREEN (-5225 2325);
DISPLAY INVISIBLE (-5225 2325);
FORCEPROP 1 LAST HDL_TAP TRUE
J 2
(-5550 2150);
DISPLAY 1.446809 (-5550 2150);
PAINT GREEN (-5550 2150);
DISPLAY INVISIBLE (-5550 2150);
FORCEPROP 1 LAST PATH I99
J 2
(-5223 2275);
DISPLAY 0.872340 (-5223 2275);
PAINT GREEN (-5223 2275);
DISPLAY INVISIBLE (-5223 2275);
FORCEADD DESIGN_NOTE..1
(-4575 1275);
FORCEPROP 0 LAST L1 CPU SYMBOLS 1-30 ARE PRELIMINARY AND SUBJECT TO CHANGE
J 0
(-4775 1150);
DISPLAY 1.021277 (-4775 1150);
PAINT ORANGE (-4775 1150);
FORCEPROP 2 LAST CDS_LIB mstr_symbols
J 0
(-4575 1275);
PAINT ORANGE (-4575 1275);
DISPLAY INVISIBLE (-4575 1275);
FORCEPROP 1 LAST COMMENT_BODY TRUE
J 0
(-4550 1375);
DISPLAY 0.978723 (-4550 1375);
PAINT ORANGE (-4550 1375);
DISPLAY INVISIBLE (-4550 1375);
FORCEADD PRELIM..10
(-4040 2565);
PAINT GRAY (-4040 2565);
FORCEPROP 2 LAST CDS_LIB mstr_misc
J 0
(-4040 2565);
PAINT ORANGE (-4040 2565);
DISPLAY INVISIBLE (-4040 2565);
FORCEPROP 1 LAST COMMENT_BODY TRUE
J 0
(-4040 2565);
PAINT ORANGE (-4040 2565);
DISPLAY INVISIBLE (-4040 2565);
FORCEADD INTEL_CORP_BPAGE..1
(0 0);
FORCEPROP 1 LAST CDS_CON_LAST_MODIFIED Tue Dec 01 11:51:37 2015
J 0
(-1425 325);
DISPLAY 1.340426 (-1425 325);
PAINT GREEN (-1425 325);
DISPLAY INVISIBLE (-1425 325);
FORCEPROP 1 LAST CUSTOM_TXT_CDS <CURRENT_DESIGN_SHEET> OF <TOTAL_DESIGN_SHEETS>
J 0
(-500 25);
PAINT GREEN (-500 25);
FORCEPROP 1 LAST CUSTOM_TXT_CDS <CON_LAST_MODIFIED>
J 0
(-1925 350);
PAINT GREEN (-1925 350);
FORCEPROP 2 LAST CUSTOM_TXT_CDS <XR_PAGE_TITLE>
J 0
(-7890 5250);
DISPLAY 0.638298 (-7890 5250);
PAINT PINK (-7890 5250);
DISPLAY INVISIBLE (-7890 5250);
FORCEPROP 1 LAST SCH_ADDRESS3 Santa Clara, CA 95052-8119
J 0
(-3975 25);
DISPLAY 0.617021 (-3975 25);
PAINT GREEN (-3975 25);
FORCEPROP 1 LAST SCH_ADDRESS2 P.O. BOX 58119
J 0
(-3975 75);
DISPLAY 0.617021 (-3975 75);
PAINT GREEN (-3975 75);
FORCEPROP 1 LAST SCH_ADDRESS1 2200 Mission College Blvd.
J 0
(-3975 125);
DISPLAY 0.617021 (-3975 125);
PAINT GREEN (-3975 125);
FORCEPROP 1 LAST SCH_TITLE SKYLAKE - SKT1 - 13 OF 21
J 0
(-7950 50);
DISPLAY 1.212766 (-7950 50);
PAINT GREEN (-7950 50);
FORCEPROP 1 LAST SCH_NUMBER H4694802
J 0
(-1300 150);
DISPLAY 1.212766 (-1300 150);
PAINT YELLOW (-1300 150);
FORCEPROP 1 LAST SCH_DEPT BESD
J 1
(-4450 100);
DISPLAY 1.212766 (-4450 100);
PAINT YELLOW (-4450 100);
FORCEPROP 1 LAST SCH_REV 2.420
J 0
(-250 150);
DISPLAY 0.978723 (-250 150);
PAINT YELLOW (-250 150);
FORCEPROP 2 LAST PAGE_BORDER TRUE
J 0
(-7890 5250);
DISPLAY 0.851064 (-7890 5250);
PAINT PINK (-7890 5250);
DISPLAY INVISIBLE (-7890 5250);
FORCEPROP 2 LAST CDS_LIB mstr_symbols
J 0
(0 0);
PAINT ORANGE (0 0);
DISPLAY INVISIBLE (0 0);
FORCEPROP 1 LAST COMMENT_BODY TRUE
J 0
(12 12);
DISPLAY 0.638298 (12 12);
PAINT GREEN (12 12);
DISPLAY INVISIBLE (12 12);
FORCEPROP 2 LAST CDS_XR_PAGE_TITLE CR-67 : @BASEBOARD_FAB2_LIB.BASEBOARD_FAB2(SCH_1):PAGE67
J 0
(-7890 5250);
DISPLAY 0.638298 (-7890 5250);
PAINT PINK (-7890 5250);
DISPLAY INVISIBLE (-7890 5250);
WIRE 17 -1 (-2850 2550)(-2850 2750);
WIRE 17 -1 (-2850 2400)(-2850 2550);
WIRE 17 -1 (-2850 2750)(-2850 2800);
WIRE 17 -1 (-2850 2800)(-2850 2850);
WIRE 17 -1 (-2850 2350)(-2850 2400);
WIRE 17 -1 (-2850 2300)(-2850 2350);
WIRE 17 -1 (-2850 2850)(-2850 2950);
WIRE 17 -1 (-2850 2950)(-2850 3000);
WIRE 17 -1 (-2850 2250)(-2850 2300);
WIRE 17 -1 (-2850 2200)(-2850 2250);
WIRE 17 -1 (-2850 3000)(-2850 3100);
WIRE 17 -1 (-2850 3500)(-2850 3100);
WIRE 17 -1 (-2850 2150)(-2850 2200);
WIRE 17 -1 (-2850 2100)(-2850 2150);
WIRE 17 -1 (-2850 3550)(-2850 3500);
WIRE 17 -1 (-2850 3550)(-2850 3725);
WIRE 17 -1 (-2850 2100)(-2850 2000);
WIRE 17 -1 (-2850 2000)(-2850 1850);
WIRE 17 -1 (-2850 3725)(-1600 3725);
FORCEPROP 2 LAST SIG_NAME UPI_CPU1_CPU0_P0P0_DP<19..0>
J 0
(-2285 3735);
DISPLAY 0.617021 (-2285 3735);
PAINT ORANGE (-2285 3735);
WIRE 17 -1 (-2525 2650)(-2525 2500);
WIRE 17 -1 (-2525 2650)(-2525 2700);
WIRE 17 -1 (-2525 2500)(-2525 2450);
WIRE 17 -1 (-2525 2450)(-2525 2050);
WIRE 17 -1 (-2525 2700)(-2525 2900);
WIRE 17 -1 (-2525 3050)(-2525 2900);
WIRE 17 -1 (-2525 1950)(-2525 2050);
WIRE 17 -1 (-2525 1900)(-2525 1950);
WIRE 17 -1 (-2525 3150)(-2525 3050);
WIRE 17 -1 (-2525 3150)(-2525 3200);
WIRE 17 -1 (-2525 1800)(-2525 1900);
WIRE 17 -1 (-2525 1750)(-2525 1800);
WIRE 17 -1 (-2525 3250)(-2525 3200);
WIRE 17 -1 (-2525 3250)(-2525 3300);
WIRE 17 -1 (-2525 1750)(-2525 1700);
WIRE 17 -1 (-2525 3300)(-2525 3350);
WIRE 17 -1 (-2525 3400)(-2525 3350);
WIRE 17 -1 (-2525 3450)(-2525 3400);
WIRE 17 -1 (-2525 3600)(-2525 3450);
WIRE 17 -1 (-2525 3650)(-2525 3600);
WIRE 17 -1 (-2525 3650)(-1600 3650);
FORCEPROP 2 LAST SIG_NAME UPI_CPU1_CPU0_P0P0_DN<19..0>
J 0
(-2285 3660);
DISPLAY 0.617021 (-2285 3660);
PAINT ORANGE (-2285 3660);
WIRE 17 -1 (-2850 1850)(-2850 1650);
WIRE 17 -1 (-2850 1650)(-2850 1600);
WIRE 17 -1 (-5275 2550)(-5275 2700);
WIRE 17 -1 (-5275 2500)(-5275 2550);
WIRE 17 -1 (-5275 2700)(-5275 2750);
WIRE 17 -1 (-5275 2750)(-5275 3150);
WIRE 17 -1 (-5275 2300)(-5275 2500);
WIRE 17 -1 (-5275 2150)(-5275 2300);
WIRE 17 -1 (-5275 3150)(-5275 3250);
WIRE 17 -1 (-5275 3300)(-5275 3250);
WIRE 17 -1 (-5275 2050)(-5275 2150);
WIRE 17 -1 (-5275 2050)(-5275 2000);
WIRE 17 -1 (-5275 3400)(-5275 3300);
WIRE 17 -1 (-5275 3450)(-5275 3400);
WIRE 17 -1 (-5275 2000)(-5275 1950);
WIRE 17 -1 (-5275 1950)(-5275 1900);
WIRE 17 -1 (-5275 3500)(-5275 3450);
WIRE 17 -1 (-5275 3700)(-5275 3500);
WIRE 17 -1 (-5275 1900)(-5275 1850);
WIRE 17 -1 (-5275 1850)(-5275 1800);
WIRE 17 -1 (-6650 3700)(-5275 3700);
FORCEPROP 2 LAST SIG_NAME UPI_CPU0_CPU1_P0P0_DP<19..0>
J 0
(-6600 3710);
DISPLAY 0.617021 (-6600 3710);
PAINT ORANGE (-6600 3710);
WIRE 17 -1 (-5275 1800)(-5275 1750);
WIRE 17 -1 (-5550 2450)(-5550 2650);
WIRE 17 -1 (-5550 2400)(-5550 2450);
WIRE 17 -1 (-5550 2650)(-5550 2800);
WIRE 17 -1 (-5550 2800)(-5550 2850);
WIRE 17 -1 (-5550 2350)(-5550 2400);
WIRE 17 -1 (-5550 2250)(-5550 2350);
WIRE 17 -1 (-5550 2850)(-5550 2900);
WIRE 17 -1 (-5550 2900)(-5550 2950);
WIRE 17 -1 (-5550 2200)(-5550 2250);
WIRE 17 -1 (-5550 2100)(-5550 2200);
WIRE 17 -1 (-5550 2950)(-5550 3000);
WIRE 17 -1 (-5550 3000)(-5550 3050);
WIRE 17 -1 (-5550 1700)(-5550 2100);
WIRE 17 -1 (-5550 1650)(-5550 1700);
WIRE 17 -1 (-5550 3050)(-5550 3100);
WIRE 17 -1 (-5550 3100)(-5550 3200);
WIRE 17 -1 (-5550 3200)(-5550 3350);
WIRE 17 -1 (-5550 3350)(-5550 3550);
WIRE 17 -1 (-5550 3550)(-5550 3600);
WIRE 17 -1 (-5550 3600)(-5550 3625);
WIRE 17 -1 (-6650 3625)(-5550 3625);
FORCEPROP 2 LAST SIG_NAME UPI_CPU0_CPU1_P0P0_DN<19..0>
J 0
(-6600 3635);
DISPLAY 0.617021 (-6600 3635);
PAINT ORANGE (-6600 3635);
WIRE 17 -1 (-5275 1750)(-5275 1600);
WIRE 16 -1 (-5175 1575)(-4850 1575);
WIRE 16 -1 (-5450 1625)(-4850 1625);
WIRE 16 -1 (-5450 1675)(-4850 1675);
WIRE 16 -1 (-5175 1725)(-4850 1725);
WIRE 16 -1 (-5175 1775)(-4850 1775);
WIRE 16 -1 (-5175 1825)(-4850 1825);
WIRE 16 -1 (-5175 1875)(-4850 1875);
WIRE 16 -1 (-5175 1925)(-4850 1925);
WIRE 16 -1 (-5175 1975)(-4850 1975);
WIRE 16 -1 (-5175 2025)(-4850 2025);
WIRE 16 -1 (-5450 2625)(-4850 2625);
WIRE 16 -1 (-5175 2675)(-4850 2675);
WIRE 16 -1 (-5175 2725)(-4850 2725);
WIRE 16 -1 (-5450 2775)(-4850 2775);
WIRE 16 -1 (-5450 2825)(-4850 2825);
WIRE 16 -1 (-5450 2875)(-4850 2875);
WIRE 16 -1 (-5450 2925)(-4850 2925);
WIRE 16 -1 (-5450 2975)(-4850 2975);
WIRE 16 -1 (-5450 3025)(-4850 3025);
WIRE 16 -1 (-5450 3075)(-4850 3075);
WIRE 16 -1 (-5175 3125)(-4850 3125);
WIRE 16 -1 (-5450 3175)(-4850 3175);
WIRE 16 -1 (-5175 3225)(-4850 3225);
WIRE 16 -1 (-5175 3275)(-4850 3275);
WIRE 16 -1 (-5450 3325)(-4850 3325);
WIRE 16 -1 (-5175 3375)(-4850 3375);
WIRE 16 -1 (-5175 3425)(-4850 3425);
WIRE 16 -1 (-5175 3475)(-4850 3475);
WIRE 16 -1 (-5450 3525)(-4850 3525);
WIRE 16 -1 (-5450 3575)(-4850 3575);
WIRE 16 -1 (-5450 2075)(-4850 2075);
WIRE 16 -1 (-5175 2125)(-4850 2125);
WIRE 16 -1 (-5450 2175)(-4850 2175);
WIRE 16 -1 (-5450 2225)(-4850 2225);
WIRE 16 -1 (-5175 2275)(-4850 2275);
WIRE 16 -1 (-5450 2325)(-4850 2325);
WIRE 16 -1 (-5450 2375)(-4850 2375);
WIRE 16 -1 (-5450 2425)(-4850 2425);
WIRE 16 -1 (-5175 2475)(-4850 2475);
WIRE 16 -1 (-5175 2525)(-4850 2525);
WIRE 16 -1 (-3250 1575)(-2950 1575);
WIRE 16 -1 (-3250 1625)(-2950 1625);
WIRE 16 -1 (-2625 1675)(-3250 1675);
WIRE 16 -1 (-2625 1725)(-3250 1725);
WIRE 16 -1 (-2625 1775)(-3250 1775);
WIRE 16 -1 (-2950 1825)(-3250 1825);
WIRE 16 -1 (-2625 1875)(-3250 1875);
WIRE 16 -1 (-2625 1925)(-3250 1925);
WIRE 16 -1 (-3250 1975)(-2950 1975);
WIRE 16 -1 (-2625 2025)(-3250 2025);
WIRE 16 -1 (-2625 2625)(-3250 2625);
WIRE 16 -1 (-2625 2675)(-3250 2675);
WIRE 16 -1 (-3250 2725)(-2950 2725);
WIRE 16 -1 (-2950 2775)(-3250 2775);
WIRE 16 -1 (-2950 2825)(-3250 2825);
WIRE 16 -1 (-2625 2875)(-3250 2875);
WIRE 16 -1 (-2950 2925)(-3250 2925);
WIRE 16 -1 (-2950 2975)(-3250 2975);
WIRE 16 -1 (-2625 3025)(-3250 3025);
WIRE 16 -1 (-2950 3075)(-3250 3075);
WIRE 16 -1 (-2625 3125)(-3250 3125);
WIRE 16 -1 (-2625 3175)(-3250 3175);
WIRE 16 -1 (-2625 3225)(-3250 3225);
WIRE 16 -1 (-2625 3275)(-3250 3275);
WIRE 16 -1 (-2625 3325)(-3250 3325);
WIRE 16 -1 (-2625 3375)(-3250 3375);
WIRE 16 -1 (-2625 3425)(-3250 3425);
WIRE 16 -1 (-2950 3475)(-3250 3475);
WIRE 16 -1 (-2950 3525)(-3250 3525);
WIRE 16 -1 (-2625 3575)(-3250 3575);
WIRE 16 -1 (-2950 2075)(-3250 2075);
WIRE 16 -1 (-2950 2125)(-3250 2125);
WIRE 16 -1 (-3250 2175)(-2950 2175);
WIRE 16 -1 (-3250 2225)(-2950 2225);
WIRE 16 -1 (-2950 2275)(-3250 2275);
WIRE 16 -1 (-3250 2325)(-2950 2325);
WIRE 16 -1 (-3250 2375)(-2950 2375);
WIRE 16 -1 (-2625 2425)(-3250 2425);
WIRE 16 -1 (-2625 2475)(-3250 2475);
WIRE 16 -1 (-3250 2525)(-2950 2525);
FORCENOTE
ROOM=CPU1
(-7925 325) 0;
DISPLAY LEFT (-7925 325);
DISPLAY 1.723404 (-7925 325);
PAINT PURPLE (-7925 325);
FORCENOTE
BOM_COST=PROC_SOCKET
(-7925 200) 0;
DISPLAY LEFT (-7925 200);
DISPLAY 1.723404 (-7925 200);
PAINT PURPLE (-7925 200);
QUIT
